FILE_TYPE = MACRO_DRAWING;
SET COLOR_WIRE YELLOW;
SET COLOR_PROP ORANGE;
SET COLOR_DOT WHITE;
SET COLOR_ARC YELLOW;
SET COLOR_BODY GREEN;
SET COLOR_NOTE PURPLE;
SET PROP_DISPLAY VALUE;
SET PAGE_NUMBER P12;
FORCEADD GND_SG..1
(-3700 3100);
FORCEPROP 3 LASTPIN (-3650 3150) SIG_NAME SG\g
J 0
(-3640 3160);
DISPLAY 0.659574 (-3640 3160);
PAINT MONO (-3640 3160);
DISPLAY INVISIBLE (-3640 3160);
FORCEPROP 1 LAST HDL_POWER SG
J 1
(-3650 3000);
DISPLAY 0.808511 (-3650 3000);
PAINT GREEN (-3650 3000);
FORCEPROP 1 LAST PATH I120
J 0
(-3665 3100);
DISPLAY 0.808511 (-3665 3100);
PAINT GREEN (-3665 3100);
DISPLAY INVISIBLE (-3665 3100);
FORCEPROP 1 LAST BODY_TYPE PLUMBING
J 0
(-3685 3085);
DISPLAY 0.808511 (-3685 3085);
PAINT GREEN (-3685 3085);
DISPLAY INVISIBLE (-3685 3085);
FORCEPROP 2 LAST CDS_LIB cls
J 0
(-3700 3100);
DISPLAY INVISIBLE (-3700 3100);
FORCEPROP 1 LAST CDS_LMAN_SYM_OUTLINE 0,0,100,-50
J 0
(-3700 3100);
DISPLAY 0.468085 (-3700 3100);
PAINT GREEN (-3700 3100);
DISPLAY INVISIBLE (-3700 3100);
FORCEADD DIODE_4_V1..1
R 1
(-3750 3350);
FORCEPROP 0 LAST PART_NUMBER SR3.3.TCT
J 0
(-4550 3550);
DISPLAY 1.021277 (-4550 3550);
FORCEPROP 1 LAST CLS_PN G122-10123-01
J 0
(-4550 3450);
DISPLAY 1.212766 (-4550 3450);
PAINT GREEN (-4550 3450);
FORCEPROP 1 LAST PATH I179
R 1
J 0
(-3800 3400);
DISPLAY 1.212766 (-3800 3400);
PAINT GREEN (-3800 3400);
DISPLAY INVISIBLE (-3800 3400);
FORCEPROP 1 LAST CDS_LMAN_SYM_OUTLINE 0,0,400,-600
R 1
J 0
(-3750 3350);
DISPLAY 0.468085 (-3750 3350);
PAINT GREEN (-3750 3350);
DISPLAY INVISIBLE (-3750 3350);
FORCEPROP 2 LAST CDS_LIB discrete
J 0
(-3750 3350);
DISPLAY INVISIBLE (-3750 3350);
FORCEPROP 1 LAST LOCATION CR4
J 0
(-4000 3350);
DISPLAY 1.212766 (-4000 3350);
PAINT GREEN (-4000 3350);
FORCEPROP 0 LASTPIN (-3650 3250) $PN 1
R 1
J 2
(-3660 3240);
DISPLAY 0.680851 (-3660 3240);
PAINT MONO (-3660 3240);
FORCEPROP 0 LASTPIN (-3350 3250) $PN 2
R 1
J 2
(-3360 3240);
DISPLAY 0.680851 (-3360 3240);
PAINT MONO (-3360 3240);
FORCEPROP 0 LASTPIN (-3400 3850) $PN 3
R 1
J 0
(-3410 3860);
DISPLAY 0.680851 (-3410 3860);
PAINT MONO (-3410 3860);
FORCEPROP 0 LASTPIN (-3650 3850) $PN 4
R 1
J 0
(-3660 3860);
DISPLAY 0.680851 (-3660 3860);
PAINT MONO (-3660 3860);
FORCEPROP 0 LAST $SEC 1
R 1
J 0
(-4550 3600);
DISPLAY 0.680851 (-4550 3600);
PAINT MONO (-4550 3600);
DISPLAY INVISIBLE (-4550 3600);
FORCEPROP 0 LAST CDS_SEC 1
R 1
J 0
(-4550 3600);
DISPLAY 1.021277 (-4550 3600);
DISPLAY INVISIBLE (-4550 3600);
FORCEADD RESISTOR..2
R 3
(-6400 9050);
FORCEPROP 0 LAST PACKAGE 0402
J 0
(-6450 9100);
DISPLAY 1.021277 (-6450 9100);
FORCEPROP 1 LAST VALUE 49.9OHM
J 2
(-5700 9050);
DISPLAY 1.212766 (-5700 9050);
PAINT GREEN (-5700 9050);
FORCEPROP 1 LAST PATH I197
R 1
J 2
(-6505 9247);
DISPLAY 1.212766 (-6505 9247);
PAINT GREEN (-6505 9247);
DISPLAY INVISIBLE (-6505 9247);
FORCEPROP 2 LAST CDS_LIB passive
R 1
J 0
(-6400 9050);
DISPLAY INVISIBLE (-6400 9050);
FORCEPROP 1 LAST CDS_LMAN_SYM_OUTLINE -50,50,50,-100
R 1
J 2
(-6400 9050);
DISPLAY 0.468085 (-6400 9050);
PAINT GREEN (-6400 9050);
DISPLAY INVISIBLE (-6400 9050);
FORCEPROP 1 LAST TOLERANCE 1%
R 1
J 2
(-6655 9247);
DISPLAY 1.212766 (-6655 9247);
PAINT GREEN (-6655 9247);
DISPLAY INVISIBLE (-6655 9247);
FORCEPROP 1 LAST CLS_PN G155-149R9-01
R 1
J 2
(-6600 9186);
DISPLAY 1.212766 (-6600 9186);
PAINT GREEN (-6600 9186);
DISPLAY INVISIBLE (-6600 9186);
FORCEPROP 1 LAST LOCATION R122
J 2
(-6600 9050);
DISPLAY 1.212766 (-6600 9050);
PAINT GREEN (-6600 9050);
FORCEPROP 0 LASTPIN (-6500 9050) $PN 1
J 2
(-6510 9060);
DISPLAY 0.680851 (-6510 9060);
PAINT MONO (-6510 9060);
FORCEPROP 0 LASTPIN (-6250 9050) $PN 2
J 0
(-6240 9060);
DISPLAY 0.680851 (-6240 9060);
PAINT MONO (-6240 9060);
FORCEPROP 0 LAST $SEC 1
R 1
J 0
(-6300 9200);
DISPLAY 0.680851 (-6300 9200);
PAINT MONO (-6300 9200);
DISPLAY INVISIBLE (-6300 9200);
FORCEPROP 0 LAST CDS_SEC 1
R 1
J 0
(-6300 9200);
DISPLAY 1.021277 (-6300 9200);
DISPLAY INVISIBLE (-6300 9200);
FORCEADD 74HCT2G125DP_TSSOP8..1
(-9550 9250);
FORCEPROP 0 LAST VALUE NC7WV125K8X
J 0
(-9550 9550);
FORCEPROP 1 LAST CLS_PN G220-00055-01
J 0
(-9550 9400);
DISPLAY 1.212766 (-9550 9400);
PAINT GREEN (-9550 9400);
FORCEPROP 1 LAST PATH I204
J 0
(-9500 9300);
DISPLAY 1.212766 (-9500 9300);
PAINT GREEN (-9500 9300);
DISPLAY INVISIBLE (-9500 9300);
FORCEPROP 2 LASTPIN (-9650 9050) SIG_NAME UN$12$74HCT2G125DPTSSOP8$I204$1A
J 0
(-9640 9060);
DISPLAY 0.659574 (-9640 9060);
PAINT MONO (-9640 9060);
DISPLAY INVISIBLE (-9640 9060);
FORCEPROP 2 LAST CDS_LIB stdlogic
J 0
(-9550 9250);
DISPLAY INVISIBLE (-9550 9250);
FORCEPROP 1 LAST CDS_LMAN_SYM_OUTLINE 0,0,500,-500
J 0
(-9550 9250);
DISPLAY 0.468085 (-9550 9250);
PAINT GREEN (-9550 9250);
DISPLAY INVISIBLE (-9550 9250);
FORCEPROP 1 LAST LOCATION U13
J 0
(-9550 9300);
DISPLAY 1.212766 (-9550 9300);
PAINT GREEN (-9550 9300);
FORCEPROP 0 LASTPIN (-9650 9050) $PN 2
J 2
(-9660 9060);
DISPLAY 0.680851 (-9660 9060);
PAINT MONO (-9660 9060);
FORCEPROP 0 LASTPIN (-9650 9150) $PN 1
J 2
(-9660 9160);
DISPLAY 0.680851 (-9660 9160);
PAINT MONO (-9660 9160);
FORCEPROP 0 LASTPIN (-8950 9050) $PN 6
J 0
(-8940 9060);
DISPLAY 0.680851 (-8940 9060);
PAINT MONO (-8940 9060);
FORCEPROP 0 LASTPIN (-9650 8950) $PN 5
J 2
(-9660 8960);
DISPLAY 0.680851 (-9660 8960);
PAINT MONO (-9660 8960);
FORCEPROP 0 LASTPIN (-9650 8850) $PN 7
J 2
(-9660 8860);
DISPLAY 0.680851 (-9660 8860);
PAINT MONO (-9660 8860);
FORCEPROP 0 LASTPIN (-8950 8950) $PN 3
J 0
(-8940 8960);
DISPLAY 0.680851 (-8940 8960);
PAINT MONO (-8940 8960);
FORCEPROP 0 LASTPIN (-8950 8850) $PN 4
J 0
(-8940 8860);
DISPLAY 0.680851 (-8940 8860);
PAINT MONO (-8940 8860);
FORCEPROP 0 LASTPIN (-8950 9150) $PN 8
J 0
(-8940 9160);
DISPLAY 0.680851 (-8940 9160);
PAINT MONO (-8940 9160);
FORCEPROP 0 LAST $SEC 1
J 0
(-9550 9600);
DISPLAY 0.680851 (-9550 9600);
PAINT MONO (-9550 9600);
DISPLAY INVISIBLE (-9550 9600);
FORCEPROP 0 LAST CDS_SEC 1
J 0
(-9550 9600);
DISPLAY 1.021277 (-9550 9600);
DISPLAY INVISIBLE (-9550 9600);
FORCEADD RESISTOR..2
R 1
(-10750 9400);
FORCEPROP 1 LAST VALUE 4.7KOHM
J 0
(-10500 9400);
DISPLAY 1.212766 (-10500 9400);
PAINT GREEN (-10500 9400);
FORCEPROP 0 LAST PACKAGE 0402
J 0
(-10800 9300);
DISPLAY 1.021277 (-10800 9300);
FORCEPROP 1 LAST PATH I206
R 1
J 0
(-10855 9203);
DISPLAY 1.212766 (-10855 9203);
PAINT GREEN (-10855 9203);
DISPLAY INVISIBLE (-10855 9203);
FORCEPROP 2 LAST CDS_LIB passive
J 0
(-10750 9400);
DISPLAY INVISIBLE (-10750 9400);
FORCEPROP 1 LAST CDS_LMAN_SYM_OUTLINE -50,50,50,-100
R 1
J 0
(-10750 9400);
DISPLAY 0.468085 (-10750 9400);
PAINT GREEN (-10750 9400);
DISPLAY INVISIBLE (-10750 9400);
FORCEPROP 1 LAST CLS_PN G155-14701-01
R 1
J 0
(-10950 9264);
DISPLAY 1.212766 (-10950 9264);
PAINT GREEN (-10950 9264);
DISPLAY INVISIBLE (-10950 9264);
FORCEPROP 1 LAST TOLERANCE 1%
R 1
J 0
(-11005 9203);
DISPLAY 1.212766 (-11005 9203);
PAINT GREEN (-11005 9203);
DISPLAY INVISIBLE (-11005 9203);
FORCEPROP 1 LAST LOCATION R377
J 0
(-11150 9400);
DISPLAY 1.212766 (-11150 9400);
PAINT GREEN (-11150 9400);
FORCEPROP 0 LASTPIN (-10850 9400) $PN 1
J 2
(-10860 9410);
DISPLAY 0.680851 (-10860 9410);
PAINT MONO (-10860 9410);
FORCEPROP 0 LASTPIN (-10600 9400) $PN 2
J 0
(-10590 9410);
DISPLAY 0.680851 (-10590 9410);
PAINT MONO (-10590 9410);
FORCEPROP 0 LAST $SEC 1
R 1
J 0
(-10550 9550);
DISPLAY 0.680851 (-10550 9550);
PAINT MONO (-10550 9550);
DISPLAY INVISIBLE (-10550 9550);
FORCEPROP 0 LAST CDS_SEC 1
R 1
J 0
(-10550 9550);
DISPLAY 1.021277 (-10550 9550);
DISPLAY INVISIBLE (-10550 9550);
FORCEADD CAPACITOR..2
(-8450 8750);
FORCEPROP 0 LAST VOLTAGE 10V
J 0
(-8400 8500);
DISPLAY 1.021277 (-8400 8500);
FORCEPROP 0 LAST PACKAGE 0402
J 0
(-8350 8700);
DISPLAY 1.021277 (-8350 8700);
FORCEPROP 1 LAST VALUE 0.1UF
J 0
(-8400 8800);
DISPLAY 1.212766 (-8400 8800);
PAINT GREEN (-8400 8800);
FORCEPROP 1 LAST PATH I207
J 0
(-8550 8800);
DISPLAY 1.212766 (-8550 8800);
PAINT GREEN (-8550 8800);
DISPLAY INVISIBLE (-8550 8800);
FORCEPROP 1 LAST CDS_LMAN_SYM_OUTLINE -50,0,50,-50
J 0
(-8450 8750);
DISPLAY 0.468085 (-8450 8750);
PAINT GREEN (-8450 8750);
DISPLAY INVISIBLE (-8450 8750);
FORCEPROP 2 LAST CDS_LIB passive
J 0
(-8450 8750);
DISPLAY INVISIBLE (-8450 8750);
FORCEPROP 1 LAST TOLERANCE 10%
J 0
(-8600 8850);
DISPLAY 1.212766 (-8600 8850);
PAINT GREEN (-8600 8850);
DISPLAY INVISIBLE (-8600 8850);
FORCEPROP 1 LAST CLS_PN G105-0B104-CK
J 0
(-8550 8800);
DISPLAY 1.212766 (-8550 8800);
PAINT GREEN (-8550 8800);
DISPLAY INVISIBLE (-8550 8800);
FORCEPROP 1 LAST $LOCATION C83
J 0
(-8400 8600);
DISPLAY 1.212766 (-8400 8600);
PAINT GREEN (-8400 8600);
FORCEPROP 0 LASTPIN (-8450 8850) $PN 1
R 1
J 0
(-8460 8860);
DISPLAY 0.680851 (-8460 8860);
PAINT MONO (-8460 8860);
FORCEPROP 0 LASTPIN (-8450 8600) $PN 2
R 1
J 2
(-8460 8590);
DISPLAY 0.680851 (-8460 8590);
PAINT MONO (-8460 8590);
FORCEPROP 0 LAST CDS_LOCATION C83
J 0
(-8400 8900);
DISPLAY 1.021277 (-8400 8900);
DISPLAY INVISIBLE (-8400 8900);
FORCEPROP 0 LAST $SEC 1
J 0
(-8400 8900);
DISPLAY 0.680851 (-8400 8900);
PAINT MONO (-8400 8900);
DISPLAY INVISIBLE (-8400 8900);
FORCEPROP 0 LAST CDS_SEC 1
J 0
(-8400 8900);
DISPLAY 1.021277 (-8400 8900);
DISPLAY INVISIBLE (-8400 8900);
FORCEADD OFFPAGE_IN..1
R 6
(-12950 8850);
FORCEPROP 2 LAST $XR1 25E6<> 
J 0
(-13350 8850);
DISPLAY 0.638298 (-13350 8850);
PAINT MONO (-13350 8850);
FORCEPROP 2 LAST $XR0 12E5> 
J 0
(-13150 8850);
DISPLAY 0.638298 (-13150 8850);
PAINT MONO (-13150 8850);
FORCEPROP 2 LAST CDS_LIB cls
J 0
(-12950 8850);
DISPLAY INVISIBLE (-12950 8850);
FORCEPROP 1 LAST CDS_LMAN_SYM_OUTLINE -50,50,50,-50
J 0
(-12950 8850);
DISPLAY 0.468085 (-12950 8850);
PAINT GREEN (-12950 8850);
DISPLAY INVISIBLE (-12950 8850);
FORCEPROP 1 LAST BODY_TYPE COMMENT
J 0
(-12940 8715);
DISPLAY 0.808511 (-12940 8715);
PAINT GREEN (-12940 8715);
DISPLAY INVISIBLE (-12940 8715);
FORCEPROP 1 LAST OFFPAGE TRUE
J 0
(-12940 8795);
DISPLAY 0.808511 (-12940 8795);
PAINT GREEN (-12940 8795);
DISPLAY INVISIBLE (-12940 8795);
FORCEPROP 2 LAST PATH I208
J 0
(-12900 8950);
DISPLAY 1.021277 (-12900 8950);
DISPLAY INVISIBLE (-12900 8950);
FORCEADD RESISTOR..2
R 3
(-6400 8950);
FORCEPROP 1 LAST VALUE 49.9OHM
J 2
(-5700 8950);
DISPLAY 1.212766 (-5700 8950);
PAINT GREEN (-5700 8950);
FORCEPROP 0 LAST PACKAGE 0402
J 0
(-6450 8850);
DISPLAY 1.021277 (-6450 8850);
FORCEPROP 1 LAST PATH I209
R 1
J 2
(-6505 9147);
DISPLAY 1.212766 (-6505 9147);
PAINT GREEN (-6505 9147);
DISPLAY INVISIBLE (-6505 9147);
FORCEPROP 1 LAST CDS_LMAN_SYM_OUTLINE -50,50,50,-100
R 1
J 2
(-6400 8950);
DISPLAY 0.468085 (-6400 8950);
PAINT GREEN (-6400 8950);
DISPLAY INVISIBLE (-6400 8950);
FORCEPROP 2 LAST CDS_LIB passive
J 0
(-6400 8950);
DISPLAY INVISIBLE (-6400 8950);
FORCEPROP 1 LAST TOLERANCE 1%
R 1
J 2
(-6655 9147);
DISPLAY 1.212766 (-6655 9147);
PAINT GREEN (-6655 9147);
DISPLAY INVISIBLE (-6655 9147);
FORCEPROP 1 LAST CLS_PN G155-149R9-01
R 1
J 2
(-6600 9086);
DISPLAY 1.212766 (-6600 9086);
PAINT GREEN (-6600 9086);
DISPLAY INVISIBLE (-6600 9086);
FORCEPROP 1 LAST $LOCATION R367
J 2
(-6600 8950);
DISPLAY 1.212766 (-6600 8950);
PAINT GREEN (-6600 8950);
FORCEPROP 0 LASTPIN (-6500 8950) $PN 1
J 2
(-6510 8960);
DISPLAY 0.680851 (-6510 8960);
PAINT MONO (-6510 8960);
FORCEPROP 0 LASTPIN (-6250 8950) $PN 2
J 0
(-6240 8960);
DISPLAY 0.680851 (-6240 8960);
PAINT MONO (-6240 8960);
FORCEPROP 0 LAST CDS_LOCATION R367
R 1
J 0
(-5850 9100);
DISPLAY 1.021277 (-5850 9100);
DISPLAY INVISIBLE (-5850 9100);
FORCEPROP 0 LAST $SEC 1
R 1
J 0
(-5850 9100);
DISPLAY 0.680851 (-5850 9100);
PAINT MONO (-5850 9100);
DISPLAY INVISIBLE (-5850 9100);
FORCEPROP 0 LAST CDS_SEC 1
R 1
J 0
(-5850 9100);
DISPLAY 1.021277 (-5850 9100);
DISPLAY INVISIBLE (-5850 9100);
FORCEADD VCC..1
(-8500 9300);
FORCEPROP 3 LASTPIN (-8450 9250) SIG_NAME XP3R3V_FPGA\g
J 0
(-8440 9260);
DISPLAY 0.659574 (-8440 9260);
PAINT MONO (-8440 9260);
DISPLAY INVISIBLE (-8440 9260);
FORCEPROP 0 LAST VOLTAGE 3.3V
J 0
(-8750 9450);
DISPLAY 1.021277 (-8750 9450);
DISPLAY BOTH (-8750 9450);
FORCEPROP 1 LAST HDL_POWER XP3R3V_FPGA
J 1
(-8445 9355);
DISPLAY 1.021277 (-8445 9355);
PAINT GREEN (-8445 9355);
FORCEPROP 1 LAST PATH I210
J 0
(-8465 9390);
DISPLAY 0.808511 (-8465 9390);
PAINT GREEN (-8465 9390);
DISPLAY INVISIBLE (-8465 9390);
FORCEPROP 1 LAST BODY_TYPE PLUMBING
J 0
(-8545 9257);
DISPLAY 0.340426 (-8545 9257);
PAINT GREEN (-8545 9257);
DISPLAY INVISIBLE (-8545 9257);
FORCEPROP 1 LAST CDS_LMAN_SYM_OUTLINE -250,250,250,-250
J 0
(-8500 9300);
DISPLAY 0.468085 (-8500 9300);
PAINT GREEN (-8500 9300);
DISPLAY INVISIBLE (-8500 9300);
FORCEPROP 2 LAST CDS_LIB cls
J 0
(-8500 9300);
DISPLAY INVISIBLE (-8500 9300);
FORCEADD GND_SG..1
(-8800 8400);
FORCEPROP 3 LASTPIN (-8750 8450) SIG_NAME SG\g
J 0
(-8740 8460);
DISPLAY 0.659574 (-8740 8460);
PAINT MONO (-8740 8460);
DISPLAY INVISIBLE (-8740 8460);
FORCEPROP 1 LAST HDL_POWER SG
J 1
(-8750 8300);
DISPLAY 0.808511 (-8750 8300);
PAINT GREEN (-8750 8300);
FORCEPROP 1 LAST BODY_TYPE PLUMBING
J 0
(-8785 8385);
DISPLAY 0.808511 (-8785 8385);
PAINT GREEN (-8785 8385);
DISPLAY INVISIBLE (-8785 8385);
FORCEPROP 1 LAST PATH I211
J 0
(-8765 8400);
DISPLAY 0.808511 (-8765 8400);
PAINT GREEN (-8765 8400);
DISPLAY INVISIBLE (-8765 8400);
FORCEPROP 2 LAST CDS_LIB cls
J 0
(-8800 8400);
DISPLAY INVISIBLE (-8800 8400);
FORCEPROP 1 LAST CDS_LMAN_SYM_OUTLINE 0,0,100,-50
J 0
(-8800 8400);
DISPLAY 0.468085 (-8800 8400);
PAINT GREEN (-8800 8400);
DISPLAY INVISIBLE (-8800 8400);
FORCEADD OFFPAGE_OUT..1
(-4900 8950);
FORCEPROP 2 LAST $XR0 11E5< 
J 0
(-4845 8950);
DISPLAY 0.638298 (-4845 8950);
PAINT MONO (-4845 8950);
FORCEPROP 1 LAST OFFPAGE TRUE
J 0
(-4890 9005);
DISPLAY 0.808511 (-4890 9005);
PAINT GREEN (-4890 9005);
DISPLAY INVISIBLE (-4890 9005);
FORCEPROP 1 LAST BODY_TYPE COMMENT
J 0
(-4890 9085);
DISPLAY 0.808511 (-4890 9085);
PAINT GREEN (-4890 9085);
DISPLAY INVISIBLE (-4890 9085);
FORCEPROP 1 LAST CDS_LMAN_SYM_OUTLINE -50,50,50,-50
J 0
(-4900 8950);
DISPLAY 0.468085 (-4900 8950);
PAINT GREEN (-4900 8950);
DISPLAY INVISIBLE (-4900 8950);
FORCEPROP 2 LAST CDS_LIB cls
J 2
(-4900 8950);
DISPLAY INVISIBLE (-4900 8950);
FORCEPROP 2 LAST PATH I212
J 2
(-4950 9050);
DISPLAY 1.021277 (-4950 9050);
DISPLAY INVISIBLE (-4950 9050);
FORCEADD 74HCT2G125DP_TSSOP8..1
(-9500 7100);
FORCEPROP 0 LAST VALUE NC7WV125K8X
J 0
(-9500 7400);
FORCEPROP 1 LAST CLS_PN G220-00055-01
J 0
(-9500 7250);
DISPLAY 1.212766 (-9500 7250);
PAINT GREEN (-9500 7250);
FORCEPROP 1 LAST PATH I226
J 0
(-9450 7150);
DISPLAY 1.212766 (-9450 7150);
PAINT GREEN (-9450 7150);
DISPLAY INVISIBLE (-9450 7150);
FORCEPROP 2 LASTPIN (-9600 6900) SIG_NAME UN$12$74HCT2G125DPTSSOP8$I226$1A
J 0
(-9590 6910);
DISPLAY 0.659574 (-9590 6910);
PAINT MONO (-9590 6910);
DISPLAY INVISIBLE (-9590 6910);
FORCEPROP 1 LAST CDS_LMAN_SYM_OUTLINE 0,0,500,-500
J 0
(-9500 7100);
DISPLAY 0.468085 (-9500 7100);
PAINT GREEN (-9500 7100);
DISPLAY INVISIBLE (-9500 7100);
FORCEPROP 2 LAST CDS_LIB stdlogic
J 0
(-9500 7100);
DISPLAY INVISIBLE (-9500 7100);
FORCEPROP 1 LAST LOCATION U14
J 0
(-9500 7150);
DISPLAY 1.212766 (-9500 7150);
PAINT GREEN (-9500 7150);
FORCEPROP 0 LASTPIN (-9600 6900) $PN 2
J 2
(-9610 6910);
DISPLAY 0.680851 (-9610 6910);
PAINT MONO (-9610 6910);
FORCEPROP 0 LASTPIN (-9600 7000) $PN 1
J 2
(-9610 7010);
DISPLAY 0.680851 (-9610 7010);
PAINT MONO (-9610 7010);
FORCEPROP 0 LASTPIN (-8900 6900) $PN 6
J 0
(-8890 6910);
DISPLAY 0.680851 (-8890 6910);
PAINT MONO (-8890 6910);
FORCEPROP 0 LASTPIN (-9600 6800) $PN 5
J 2
(-9610 6810);
DISPLAY 0.680851 (-9610 6810);
PAINT MONO (-9610 6810);
FORCEPROP 0 LASTPIN (-9600 6700) $PN 7
J 2
(-9610 6710);
DISPLAY 0.680851 (-9610 6710);
PAINT MONO (-9610 6710);
FORCEPROP 0 LASTPIN (-8900 6800) $PN 3
J 0
(-8890 6810);
DISPLAY 0.680851 (-8890 6810);
PAINT MONO (-8890 6810);
FORCEPROP 0 LASTPIN (-8900 6700) $PN 4
J 0
(-8890 6710);
DISPLAY 0.680851 (-8890 6710);
PAINT MONO (-8890 6710);
FORCEPROP 0 LASTPIN (-8900 7000) $PN 8
J 0
(-8890 7010);
DISPLAY 0.680851 (-8890 7010);
PAINT MONO (-8890 7010);
FORCEPROP 0 LAST $SEC 1
J 0
(-9500 7450);
DISPLAY 0.680851 (-9500 7450);
PAINT MONO (-9500 7450);
DISPLAY INVISIBLE (-9500 7450);
FORCEPROP 0 LAST CDS_SEC 1
J 0
(-9500 7450);
DISPLAY 1.021277 (-9500 7450);
DISPLAY INVISIBLE (-9500 7450);
FORCEADD OFFPAGE_OUT..1
(-4850 6800);
FORCEPROP 2 LAST $XR0 11F5< 
J 0
(-4795 6800);
DISPLAY 0.638298 (-4795 6800);
PAINT MONO (-4795 6800);
FORCEPROP 2 LAST PATH I227
J 0
(-4800 6900);
DISPLAY 1.021277 (-4800 6900);
DISPLAY INVISIBLE (-4800 6900);
FORCEPROP 1 LAST OFFPAGE TRUE
J 0
(-4840 6855);
DISPLAY 0.808511 (-4840 6855);
PAINT GREEN (-4840 6855);
DISPLAY INVISIBLE (-4840 6855);
FORCEPROP 2 LAST CDS_LIB cls
J 2
(-4850 6800);
DISPLAY INVISIBLE (-4850 6800);
FORCEPROP 1 LAST CDS_LMAN_SYM_OUTLINE -50,50,50,-50
J 0
(-4850 6800);
DISPLAY 0.468085 (-4850 6800);
PAINT GREEN (-4850 6800);
DISPLAY INVISIBLE (-4850 6800);
FORCEPROP 1 LAST BODY_TYPE COMMENT
J 0
(-4840 6935);
DISPLAY 0.808511 (-4840 6935);
PAINT GREEN (-4840 6935);
DISPLAY INVISIBLE (-4840 6935);
FORCEADD RESISTOR..2
R 3
(-6350 6900);
FORCEPROP 1 LAST VALUE 49.9OHM
J 2
(-5650 6900);
DISPLAY 1.212766 (-5650 6900);
PAINT GREEN (-5650 6900);
FORCEPROP 0 LAST PACKAGE 0402
J 0
(-6400 6950);
DISPLAY 1.021277 (-6400 6950);
FORCEPROP 1 LAST PATH I228
R 1
J 2
(-6455 7097);
DISPLAY 1.212766 (-6455 7097);
PAINT GREEN (-6455 7097);
DISPLAY INVISIBLE (-6455 7097);
FORCEPROP 1 LAST CDS_LMAN_SYM_OUTLINE -50,50,50,-100
R 1
J 2
(-6350 6900);
DISPLAY 0.468085 (-6350 6900);
PAINT GREEN (-6350 6900);
DISPLAY INVISIBLE (-6350 6900);
FORCEPROP 2 LAST CDS_LIB passive
R 1
J 0
(-6350 6900);
DISPLAY INVISIBLE (-6350 6900);
FORCEPROP 1 LAST TOLERANCE 1%
R 1
J 2
(-6605 7097);
DISPLAY 1.212766 (-6605 7097);
PAINT GREEN (-6605 7097);
DISPLAY INVISIBLE (-6605 7097);
FORCEPROP 1 LAST CLS_PN G155-149R9-01
R 1
J 2
(-6550 7036);
DISPLAY 1.212766 (-6550 7036);
PAINT GREEN (-6550 7036);
DISPLAY INVISIBLE (-6550 7036);
FORCEPROP 1 LAST LOCATION R123
J 2
(-6550 6900);
DISPLAY 1.212766 (-6550 6900);
PAINT GREEN (-6550 6900);
FORCEPROP 0 LASTPIN (-6450 6900) $PN 1
J 2
(-6460 6910);
DISPLAY 0.680851 (-6460 6910);
PAINT MONO (-6460 6910);
FORCEPROP 0 LASTPIN (-6200 6900) $PN 2
J 0
(-6190 6910);
DISPLAY 0.680851 (-6190 6910);
PAINT MONO (-6190 6910);
FORCEPROP 0 LAST $SEC 1
R 1
J 0
(-6250 7050);
DISPLAY 0.680851 (-6250 7050);
PAINT MONO (-6250 7050);
DISPLAY INVISIBLE (-6250 7050);
FORCEPROP 0 LAST CDS_SEC 1
R 1
J 0
(-6250 7050);
DISPLAY 1.021277 (-6250 7050);
DISPLAY INVISIBLE (-6250 7050);
FORCEADD RESISTOR..2
R 3
(-6350 6800);
FORCEPROP 0 LAST PACKAGE 0402
J 0
(-6400 6700);
DISPLAY 1.021277 (-6400 6700);
FORCEPROP 1 LAST VALUE 49.9OHM
J 2
(-5650 6800);
DISPLAY 1.212766 (-5650 6800);
PAINT GREEN (-5650 6800);
FORCEPROP 1 LAST PATH I229
R 1
J 2
(-6455 6997);
DISPLAY 1.212766 (-6455 6997);
PAINT GREEN (-6455 6997);
DISPLAY INVISIBLE (-6455 6997);
FORCEPROP 2 LAST CDS_LIB passive
J 0
(-6350 6800);
DISPLAY INVISIBLE (-6350 6800);
FORCEPROP 1 LAST CDS_LMAN_SYM_OUTLINE -50,50,50,-100
R 1
J 2
(-6350 6800);
DISPLAY 0.468085 (-6350 6800);
PAINT GREEN (-6350 6800);
DISPLAY INVISIBLE (-6350 6800);
FORCEPROP 1 LAST TOLERANCE 1%
R 1
J 2
(-6605 6997);
DISPLAY 1.212766 (-6605 6997);
PAINT GREEN (-6605 6997);
DISPLAY INVISIBLE (-6605 6997);
FORCEPROP 1 LAST CLS_PN G155-149R9-01
R 1
J 2
(-6550 6936);
DISPLAY 1.212766 (-6550 6936);
PAINT GREEN (-6550 6936);
DISPLAY INVISIBLE (-6550 6936);
FORCEPROP 1 LAST LOCATION R370
J 2
(-6550 6800);
DISPLAY 1.212766 (-6550 6800);
PAINT GREEN (-6550 6800);
FORCEPROP 0 LASTPIN (-6450 6800) $PN 1
J 2
(-6460 6810);
DISPLAY 0.680851 (-6460 6810);
PAINT MONO (-6460 6810);
FORCEPROP 0 LASTPIN (-6200 6800) $PN 2
J 0
(-6190 6810);
DISPLAY 0.680851 (-6190 6810);
PAINT MONO (-6190 6810);
FORCEPROP 0 LAST $SEC 1
R 1
J 0
(-5800 6950);
DISPLAY 0.680851 (-5800 6950);
PAINT MONO (-5800 6950);
DISPLAY INVISIBLE (-5800 6950);
FORCEPROP 0 LAST CDS_SEC 1
R 1
J 0
(-5800 6950);
DISPLAY 1.021277 (-5800 6950);
DISPLAY INVISIBLE (-5800 6950);
FORCEADD VCC..1
(-8450 7150);
FORCEPROP 3 LASTPIN (-8400 7100) SIG_NAME XP3R3V_FPGA\g
J 0
(-8390 7110);
DISPLAY 0.659574 (-8390 7110);
PAINT MONO (-8390 7110);
DISPLAY INVISIBLE (-8390 7110);
FORCEPROP 1 LAST HDL_POWER XP3R3V_FPGA
J 1
(-8395 7205);
DISPLAY 1.021277 (-8395 7205);
PAINT GREEN (-8395 7205);
FORCEPROP 0 LAST VOLTAGE 3.3V
J 0
(-8700 7300);
DISPLAY 1.021277 (-8700 7300);
DISPLAY BOTH (-8700 7300);
FORCEPROP 1 LAST PATH I230
J 0
(-8415 7240);
DISPLAY 0.808511 (-8415 7240);
PAINT GREEN (-8415 7240);
DISPLAY INVISIBLE (-8415 7240);
FORCEPROP 1 LAST BODY_TYPE PLUMBING
J 0
(-8495 7107);
DISPLAY 0.340426 (-8495 7107);
PAINT GREEN (-8495 7107);
DISPLAY INVISIBLE (-8495 7107);
FORCEPROP 2 LAST CDS_LIB cls
J 0
(-8450 7150);
DISPLAY INVISIBLE (-8450 7150);
FORCEPROP 1 LAST CDS_LMAN_SYM_OUTLINE -250,250,250,-250
J 0
(-8450 7150);
DISPLAY 0.468085 (-8450 7150);
PAINT GREEN (-8450 7150);
DISPLAY INVISIBLE (-8450 7150);
FORCEADD CAPACITOR..2
(-8400 6600);
FORCEPROP 0 LAST VOLTAGE 10V
J 0
(-8350 6400);
DISPLAY 1.021277 (-8350 6400);
FORCEPROP 0 LAST PACKAGE 0402
J 0
(-8300 6550);
DISPLAY 1.021277 (-8300 6550);
FORCEPROP 1 LAST VALUE 0.1UF
J 0
(-8350 6650);
DISPLAY 1.212766 (-8350 6650);
PAINT GREEN (-8350 6650);
FORCEPROP 1 LAST PATH I231
J 0
(-8500 6650);
DISPLAY 1.212766 (-8500 6650);
PAINT GREEN (-8500 6650);
DISPLAY INVISIBLE (-8500 6650);
FORCEPROP 1 LAST CLS_PN G105-0B104-CK
J 0
(-8500 6650);
DISPLAY 1.212766 (-8500 6650);
PAINT GREEN (-8500 6650);
DISPLAY INVISIBLE (-8500 6650);
FORCEPROP 1 LAST TOLERANCE 10%
J 0
(-8550 6700);
DISPLAY 1.212766 (-8550 6700);
PAINT GREEN (-8550 6700);
DISPLAY INVISIBLE (-8550 6700);
FORCEPROP 2 LAST CDS_LIB passive
J 0
(-8400 6600);
DISPLAY INVISIBLE (-8400 6600);
FORCEPROP 1 LAST CDS_LMAN_SYM_OUTLINE -50,0,50,-50
J 0
(-8400 6600);
DISPLAY 0.468085 (-8400 6600);
PAINT GREEN (-8400 6600);
DISPLAY INVISIBLE (-8400 6600);
FORCEPROP 1 LAST LOCATION C82
J 0
(-8350 6450);
DISPLAY 1.212766 (-8350 6450);
PAINT GREEN (-8350 6450);
FORCEPROP 0 LASTPIN (-8400 6700) $PN 1
R 1
J 0
(-8410 6710);
DISPLAY 0.680851 (-8410 6710);
PAINT MONO (-8410 6710);
FORCEPROP 0 LASTPIN (-8400 6450) $PN 2
R 1
J 2
(-8410 6440);
DISPLAY 0.680851 (-8410 6440);
PAINT MONO (-8410 6440);
FORCEPROP 0 LAST $SEC 1
J 0
(-8350 6750);
DISPLAY 0.680851 (-8350 6750);
PAINT MONO (-8350 6750);
DISPLAY INVISIBLE (-8350 6750);
FORCEPROP 0 LAST CDS_SEC 1
J 0
(-8350 6750);
DISPLAY 1.021277 (-8350 6750);
DISPLAY INVISIBLE (-8350 6750);
FORCEADD GND_SG..1
(-8750 6250);
FORCEPROP 3 LASTPIN (-8700 6300) SIG_NAME SG\g
J 0
(-8690 6310);
DISPLAY 0.659574 (-8690 6310);
PAINT MONO (-8690 6310);
DISPLAY INVISIBLE (-8690 6310);
FORCEPROP 1 LAST HDL_POWER SG
J 1
(-8700 6150);
DISPLAY 0.808511 (-8700 6150);
PAINT GREEN (-8700 6150);
FORCEPROP 1 LAST PATH I232
J 0
(-8715 6250);
DISPLAY 0.808511 (-8715 6250);
PAINT GREEN (-8715 6250);
DISPLAY INVISIBLE (-8715 6250);
FORCEPROP 1 LAST BODY_TYPE PLUMBING
J 0
(-8735 6235);
DISPLAY 0.808511 (-8735 6235);
PAINT GREEN (-8735 6235);
DISPLAY INVISIBLE (-8735 6235);
FORCEPROP 2 LAST CDS_LIB cls
J 0
(-8750 6250);
DISPLAY INVISIBLE (-8750 6250);
FORCEPROP 1 LAST CDS_LMAN_SYM_OUTLINE 0,0,100,-50
J 0
(-8750 6250);
DISPLAY 0.468085 (-8750 6250);
PAINT GREEN (-8750 6250);
DISPLAY INVISIBLE (-8750 6250);
FORCEADD RESISTOR..2
R 1
(-10700 7350);
FORCEPROP 1 LAST VALUE 4.7KOHM
J 0
(-10450 7350);
DISPLAY 1.212766 (-10450 7350);
PAINT GREEN (-10450 7350);
FORCEPROP 0 LAST PACKAGE 0402
J 0
(-10750 7400);
DISPLAY 1.021277 (-10750 7400);
FORCEPROP 1 LAST PATH I233
R 1
J 0
(-10805 7153);
DISPLAY 1.212766 (-10805 7153);
PAINT GREEN (-10805 7153);
DISPLAY INVISIBLE (-10805 7153);
FORCEPROP 1 LAST CLS_PN G155-14701-01
R 1
J 0
(-10900 7214);
DISPLAY 1.212766 (-10900 7214);
PAINT GREEN (-10900 7214);
DISPLAY INVISIBLE (-10900 7214);
FORCEPROP 1 LAST CDS_LMAN_SYM_OUTLINE -50,50,50,-100
R 1
J 0
(-10700 7350);
DISPLAY 0.468085 (-10700 7350);
PAINT GREEN (-10700 7350);
DISPLAY INVISIBLE (-10700 7350);
FORCEPROP 2 LAST CDS_LIB passive
J 0
(-10700 7350);
DISPLAY INVISIBLE (-10700 7350);
FORCEPROP 1 LAST TOLERANCE 1%
R 1
J 0
(-10955 7153);
DISPLAY 1.212766 (-10955 7153);
PAINT GREEN (-10955 7153);
DISPLAY INVISIBLE (-10955 7153);
FORCEPROP 1 LAST LOCATION R368
J 0
(-11100 7350);
DISPLAY 1.212766 (-11100 7350);
PAINT GREEN (-11100 7350);
FORCEPROP 0 LASTPIN (-10800 7350) $PN 1
J 2
(-10810 7360);
DISPLAY 0.680851 (-10810 7360);
PAINT MONO (-10810 7360);
FORCEPROP 0 LASTPIN (-10550 7350) $PN 2
J 0
(-10540 7360);
DISPLAY 0.680851 (-10540 7360);
PAINT MONO (-10540 7360);
FORCEPROP 0 LAST $SEC 1
R 1
J 0
(-10500 7450);
DISPLAY 0.680851 (-10500 7450);
PAINT MONO (-10500 7450);
DISPLAY INVISIBLE (-10500 7450);
FORCEPROP 0 LAST CDS_SEC 1
R 1
J 0
(-10500 7450);
DISPLAY 1.021277 (-10500 7450);
DISPLAY INVISIBLE (-10500 7450);
FORCEADD RESISTOR..2
R 1
(-10700 7250);
FORCEPROP 0 LAST PACKAGE 0402
J 0
(-10750 7150);
DISPLAY 1.021277 (-10750 7150);
FORCEPROP 1 LAST VALUE 4.7KOHM
J 0
(-10450 7250);
DISPLAY 1.212766 (-10450 7250);
PAINT GREEN (-10450 7250);
FORCEPROP 1 LAST PATH I234
R 1
J 0
(-10805 7053);
DISPLAY 1.212766 (-10805 7053);
PAINT GREEN (-10805 7053);
DISPLAY INVISIBLE (-10805 7053);
FORCEPROP 2 LAST CDS_LIB passive
J 0
(-10700 7250);
DISPLAY INVISIBLE (-10700 7250);
FORCEPROP 1 LAST CDS_LMAN_SYM_OUTLINE -50,50,50,-100
R 1
J 0
(-10700 7250);
DISPLAY 0.468085 (-10700 7250);
PAINT GREEN (-10700 7250);
DISPLAY INVISIBLE (-10700 7250);
FORCEPROP 1 LAST CLS_PN G155-14701-01
R 1
J 0
(-10900 7114);
DISPLAY 1.212766 (-10900 7114);
PAINT GREEN (-10900 7114);
DISPLAY INVISIBLE (-10900 7114);
FORCEPROP 1 LAST TOLERANCE 1%
R 1
J 0
(-10955 7053);
DISPLAY 1.212766 (-10955 7053);
PAINT GREEN (-10955 7053);
DISPLAY INVISIBLE (-10955 7053);
FORCEPROP 1 LAST LOCATION R379
J 0
(-11100 7250);
DISPLAY 1.212766 (-11100 7250);
PAINT GREEN (-11100 7250);
FORCEPROP 0 LASTPIN (-10800 7250) $PN 1
J 2
(-10810 7260);
DISPLAY 0.680851 (-10810 7260);
PAINT MONO (-10810 7260);
FORCEPROP 0 LASTPIN (-10550 7250) $PN 2
J 0
(-10540 7260);
DISPLAY 0.680851 (-10540 7260);
PAINT MONO (-10540 7260);
FORCEPROP 0 LAST $SEC 1
R 1
J 0
(-10500 7400);
DISPLAY 0.680851 (-10500 7400);
PAINT MONO (-10500 7400);
DISPLAY INVISIBLE (-10500 7400);
FORCEPROP 0 LAST CDS_SEC 1
R 1
J 0
(-10500 7400);
DISPLAY 1.021277 (-10500 7400);
DISPLAY INVISIBLE (-10500 7400);
FORCEADD VCC..1
(-11350 7450);
FORCEPROP 3 LASTPIN (-11300 7400) SIG_NAME XP3R3V_FPGA\g
J 0
(-11290 7410);
DISPLAY 0.659574 (-11290 7410);
PAINT MONO (-11290 7410);
DISPLAY INVISIBLE (-11290 7410);
FORCEPROP 0 LAST VOLTAGE 3.3V
J 0
(-11600 7600);
DISPLAY 1.021277 (-11600 7600);
DISPLAY BOTH (-11600 7600);
FORCEPROP 1 LAST HDL_POWER XP3R3V_FPGA
J 1
(-11295 7505);
DISPLAY 1.021277 (-11295 7505);
PAINT GREEN (-11295 7505);
FORCEPROP 1 LAST PATH I236
J 0
(-11315 7540);
DISPLAY 0.808511 (-11315 7540);
PAINT GREEN (-11315 7540);
DISPLAY INVISIBLE (-11315 7540);
FORCEPROP 1 LAST BODY_TYPE PLUMBING
J 0
(-11395 7407);
DISPLAY 0.340426 (-11395 7407);
PAINT GREEN (-11395 7407);
DISPLAY INVISIBLE (-11395 7407);
FORCEPROP 2 LAST CDS_LIB cls
J 0
(-11350 7450);
DISPLAY INVISIBLE (-11350 7450);
FORCEPROP 1 LAST CDS_LMAN_SYM_OUTLINE -250,250,250,-250
J 0
(-11350 7450);
DISPLAY 0.468085 (-11350 7450);
PAINT GREEN (-11350 7450);
DISPLAY INVISIBLE (-11350 7450);
FORCEADD RESISTOR..2
R 3
(-10700 6900);
FORCEPROP 0 LAST PACKAGE 0402
J 0
(-10750 6950);
DISPLAY 0.808511 (-10750 6950);
FORCEPROP 1 LAST VALUE 100OHM
J 2
(-10100 6900);
DISPLAY 1.212766 (-10100 6900);
PAINT GREEN (-10100 6900);
FORCEPROP 1 LAST CLS_PN G155-11000-01
R 1
J 2
(-10900 7036);
DISPLAY 1.212766 (-10900 7036);
PAINT GREEN (-10900 7036);
DISPLAY INVISIBLE (-10900 7036);
FORCEPROP 2 LAST CDS_LIB passive
J 0
(-10700 6900);
DISPLAY INVISIBLE (-10700 6900);
FORCEPROP 1 LAST CDS_LMAN_SYM_OUTLINE -50,50,50,-100
R 1
J 2
(-10700 6900);
DISPLAY 0.468085 (-10700 6900);
PAINT GREEN (-10700 6900);
DISPLAY INVISIBLE (-10700 6900);
FORCEPROP 1 LAST PATH I237
R 1
J 2
(-10805 7097);
DISPLAY 1.212766 (-10805 7097);
PAINT GREEN (-10805 7097);
DISPLAY INVISIBLE (-10805 7097);
FORCEPROP 1 LAST TOLERANCE 1%
R 1
J 2
(-10955 7097);
DISPLAY 1.212766 (-10955 7097);
PAINT GREEN (-10955 7097);
DISPLAY INVISIBLE (-10955 7097);
FORCEPROP 1 LAST LOCATION R157
J 2
(-10850 6900);
DISPLAY 1.212766 (-10850 6900);
PAINT GREEN (-10850 6900);
FORCEPROP 0 LASTPIN (-10800 6900) $PN 1
J 2
(-10810 6910);
DISPLAY 0.680851 (-10810 6910);
PAINT MONO (-10810 6910);
FORCEPROP 0 LASTPIN (-10550 6900) $PN 2
J 0
(-10540 6910);
DISPLAY 0.680851 (-10540 6910);
PAINT MONO (-10540 6910);
FORCEPROP 0 LAST $SEC 1
R 1
J 0
(-10150 7050);
DISPLAY 0.680851 (-10150 7050);
PAINT MONO (-10150 7050);
DISPLAY INVISIBLE (-10150 7050);
FORCEPROP 0 LAST CDS_SEC 1
R 1
J 0
(-10150 7050);
DISPLAY 1.021277 (-10150 7050);
DISPLAY INVISIBLE (-10150 7050);
FORCEADD OFFPAGE_IN..1
R 6
(-12950 7000);
FORCEPROP 2 LAST $XR0 12D5> 
J 0
(-13133 7000);
DISPLAY 0.638298 (-13133 7000);
PAINT MONO (-13133 7000);
FORCEPROP 2 LAST $XR1 25F6<> 
J 0
(-13343 7000);
DISPLAY 0.638298 (-13343 7000);
PAINT MONO (-13343 7000);
FORCEPROP 1 LAST BODY_TYPE COMMENT
J 0
(-12940 6865);
DISPLAY 0.808511 (-12940 6865);
PAINT GREEN (-12940 6865);
DISPLAY INVISIBLE (-12940 6865);
FORCEPROP 1 LAST CDS_LMAN_SYM_OUTLINE -50,50,50,-50
J 0
(-12950 7000);
DISPLAY 0.468085 (-12950 7000);
PAINT GREEN (-12950 7000);
DISPLAY INVISIBLE (-12950 7000);
FORCEPROP 2 LAST CDS_LIB cls
J 0
(-12950 7000);
DISPLAY INVISIBLE (-12950 7000);
FORCEPROP 1 LAST OFFPAGE TRUE
J 0
(-12940 6945);
DISPLAY 0.808511 (-12940 6945);
PAINT GREEN (-12940 6945);
DISPLAY INVISIBLE (-12940 6945);
FORCEPROP 2 LAST PATH I239
J 0
(-13100 7050);
DISPLAY 1.021277 (-13100 7050);
DISPLAY INVISIBLE (-13100 7050);
FORCEADD OFFPAGE_IN..1
R 6
(-12950 6900);
FORCEPROP 2 LAST $XR0 11F5> 
J 0
(-13133 6900);
DISPLAY 0.638298 (-13133 6900);
PAINT MONO (-13133 6900);
FORCEPROP 2 LAST CDS_LIB cls
J 0
(-12950 6900);
DISPLAY INVISIBLE (-12950 6900);
FORCEPROP 1 LAST CDS_LMAN_SYM_OUTLINE -50,50,50,-50
J 0
(-12950 6900);
DISPLAY 0.468085 (-12950 6900);
PAINT GREEN (-12950 6900);
DISPLAY INVISIBLE (-12950 6900);
FORCEPROP 1 LAST BODY_TYPE COMMENT
J 0
(-12940 6765);
DISPLAY 0.808511 (-12940 6765);
PAINT GREEN (-12940 6765);
DISPLAY INVISIBLE (-12940 6765);
FORCEPROP 1 LAST OFFPAGE TRUE
J 0
(-12940 6845);
DISPLAY 0.808511 (-12940 6845);
PAINT GREEN (-12940 6845);
DISPLAY INVISIBLE (-12940 6845);
FORCEPROP 2 LAST PATH I240
J 0
(-13100 6950);
DISPLAY 1.021277 (-13100 6950);
DISPLAY INVISIBLE (-13100 6950);
FORCEADD OFFPAGE_IN..1
R 6
(-12950 6700);
FORCEPROP 2 LAST $XR0 12D5> 
J 0
(-13133 6700);
DISPLAY 0.638298 (-13133 6700);
PAINT MONO (-13133 6700);
FORCEPROP 2 LAST $XR1 25E6<> 
J 0
(-13343 6700);
DISPLAY 0.638298 (-13343 6700);
PAINT MONO (-13343 6700);
FORCEPROP 1 LAST BODY_TYPE COMMENT
J 0
(-12940 6565);
DISPLAY 0.808511 (-12940 6565);
PAINT GREEN (-12940 6565);
DISPLAY INVISIBLE (-12940 6565);
FORCEPROP 1 LAST CDS_LMAN_SYM_OUTLINE -50,50,50,-50
J 0
(-12950 6700);
DISPLAY 0.468085 (-12950 6700);
PAINT GREEN (-12950 6700);
DISPLAY INVISIBLE (-12950 6700);
FORCEPROP 2 LAST CDS_LIB cls
J 0
(-12950 6700);
DISPLAY INVISIBLE (-12950 6700);
FORCEPROP 1 LAST OFFPAGE TRUE
J 0
(-12940 6645);
DISPLAY 0.808511 (-12940 6645);
PAINT GREEN (-12940 6645);
DISPLAY INVISIBLE (-12940 6645);
FORCEPROP 2 LAST PATH I241
J 0
(-12900 6800);
DISPLAY 1.021277 (-12900 6800);
DISPLAY INVISIBLE (-12900 6800);
FORCEADD 74HCT2G125DP_TSSOP8..1
(-9500 4950);
FORCEPROP 1 LAST CLS_PN G220-00055-01
J 0
(-9500 5100);
DISPLAY 1.212766 (-9500 5100);
PAINT GREEN (-9500 5100);
FORCEPROP 0 LAST VALUE NC7WV125K8X
J 0
(-9500 5250);
FORCEPROP 1 LAST PATH I255
J 0
(-9450 5000);
DISPLAY 1.212766 (-9450 5000);
PAINT GREEN (-9450 5000);
DISPLAY INVISIBLE (-9450 5000);
FORCEPROP 2 LASTPIN (-9600 4750) SIG_NAME UN$12$74HCT2G125DPTSSOP8$I255$1A
J 0
(-9590 4760);
DISPLAY 0.659574 (-9590 4760);
PAINT MONO (-9590 4760);
DISPLAY INVISIBLE (-9590 4760);
FORCEPROP 2 LAST CDS_LIB stdlogic
J 0
(-9500 4950);
DISPLAY INVISIBLE (-9500 4950);
FORCEPROP 1 LAST CDS_LMAN_SYM_OUTLINE 0,0,500,-500
J 0
(-9500 4950);
DISPLAY 0.468085 (-9500 4950);
PAINT GREEN (-9500 4950);
DISPLAY INVISIBLE (-9500 4950);
FORCEPROP 1 LAST LOCATION U15
J 0
(-9500 5000);
DISPLAY 1.212766 (-9500 5000);
PAINT GREEN (-9500 5000);
FORCEPROP 0 LASTPIN (-9600 4750) $PN 2
J 2
(-9610 4760);
DISPLAY 0.680851 (-9610 4760);
PAINT MONO (-9610 4760);
FORCEPROP 0 LASTPIN (-9600 4850) $PN 1
J 2
(-9610 4860);
DISPLAY 0.680851 (-9610 4860);
PAINT MONO (-9610 4860);
FORCEPROP 0 LASTPIN (-8900 4750) $PN 6
J 0
(-8890 4760);
DISPLAY 0.680851 (-8890 4760);
PAINT MONO (-8890 4760);
FORCEPROP 0 LASTPIN (-9600 4650) $PN 5
J 2
(-9610 4660);
DISPLAY 0.680851 (-9610 4660);
PAINT MONO (-9610 4660);
FORCEPROP 0 LASTPIN (-9600 4550) $PN 7
J 2
(-9610 4560);
DISPLAY 0.680851 (-9610 4560);
PAINT MONO (-9610 4560);
FORCEPROP 0 LASTPIN (-8900 4650) $PN 3
J 0
(-8890 4660);
DISPLAY 0.680851 (-8890 4660);
PAINT MONO (-8890 4660);
FORCEPROP 0 LASTPIN (-8900 4550) $PN 4
J 0
(-8890 4560);
DISPLAY 0.680851 (-8890 4560);
PAINT MONO (-8890 4560);
FORCEPROP 0 LASTPIN (-8900 4850) $PN 8
J 0
(-8890 4860);
DISPLAY 0.680851 (-8890 4860);
PAINT MONO (-8890 4860);
FORCEPROP 0 LAST $SEC 1
J 0
(-9500 5300);
DISPLAY 0.680851 (-9500 5300);
PAINT MONO (-9500 5300);
DISPLAY INVISIBLE (-9500 5300);
FORCEPROP 0 LAST CDS_SEC 1
J 0
(-9500 5300);
DISPLAY 1.021277 (-9500 5300);
DISPLAY INVISIBLE (-9500 5300);
FORCEADD OFFPAGE_OUT..1
(-4850 4650);
FORCEPROP 2 LAST $XR0 11E12< 
J 0
(-4795 4650);
DISPLAY 0.638298 (-4795 4650);
PAINT MONO (-4795 4650);
FORCEPROP 2 LAST PATH I256
J 0
(-4800 4750);
DISPLAY 1.021277 (-4800 4750);
DISPLAY INVISIBLE (-4800 4750);
FORCEPROP 1 LAST OFFPAGE TRUE
J 0
(-4840 4705);
DISPLAY 0.808511 (-4840 4705);
PAINT GREEN (-4840 4705);
DISPLAY INVISIBLE (-4840 4705);
FORCEPROP 1 LAST BODY_TYPE COMMENT
J 0
(-4840 4785);
DISPLAY 0.808511 (-4840 4785);
PAINT GREEN (-4840 4785);
DISPLAY INVISIBLE (-4840 4785);
FORCEPROP 1 LAST CDS_LMAN_SYM_OUTLINE -50,50,50,-50
J 0
(-4850 4650);
DISPLAY 0.468085 (-4850 4650);
PAINT GREEN (-4850 4650);
DISPLAY INVISIBLE (-4850 4650);
FORCEPROP 2 LAST CDS_LIB cls
J 2
(-4850 4650);
DISPLAY INVISIBLE (-4850 4650);
FORCEADD RESISTOR..2
R 3
(-6350 4750);
FORCEPROP 0 LAST PACKAGE 0402
J 0
(-6400 4800);
DISPLAY 1.021277 (-6400 4800);
FORCEPROP 1 LAST VALUE 49.9OHM
J 2
(-5650 4750);
DISPLAY 1.212766 (-5650 4750);
PAINT GREEN (-5650 4750);
FORCEPROP 1 LAST PATH I257
R 1
J 2
(-6455 4947);
DISPLAY 1.212766 (-6455 4947);
PAINT GREEN (-6455 4947);
DISPLAY INVISIBLE (-6455 4947);
FORCEPROP 2 LAST CDS_LIB passive
R 1
J 0
(-6350 4750);
DISPLAY INVISIBLE (-6350 4750);
FORCEPROP 1 LAST CDS_LMAN_SYM_OUTLINE -50,50,50,-100
R 1
J 2
(-6350 4750);
DISPLAY 0.468085 (-6350 4750);
PAINT GREEN (-6350 4750);
DISPLAY INVISIBLE (-6350 4750);
FORCEPROP 1 LAST TOLERANCE 1%
R 1
J 2
(-6605 4947);
DISPLAY 1.212766 (-6605 4947);
PAINT GREEN (-6605 4947);
DISPLAY INVISIBLE (-6605 4947);
FORCEPROP 1 LAST CLS_PN G155-149R9-01
R 1
J 2
(-6550 4886);
DISPLAY 1.212766 (-6550 4886);
PAINT GREEN (-6550 4886);
DISPLAY INVISIBLE (-6550 4886);
FORCEPROP 1 LAST LOCATION R127
J 2
(-6550 4750);
DISPLAY 1.212766 (-6550 4750);
PAINT GREEN (-6550 4750);
FORCEPROP 0 LASTPIN (-6450 4750) $PN 1
J 2
(-6460 4760);
DISPLAY 0.680851 (-6460 4760);
PAINT MONO (-6460 4760);
FORCEPROP 0 LASTPIN (-6200 4750) $PN 2
J 0
(-6190 4760);
DISPLAY 0.680851 (-6190 4760);
PAINT MONO (-6190 4760);
FORCEPROP 0 LAST $SEC 1
R 1
J 0
(-6250 4900);
DISPLAY 0.680851 (-6250 4900);
PAINT MONO (-6250 4900);
DISPLAY INVISIBLE (-6250 4900);
FORCEPROP 0 LAST CDS_SEC 1
R 1
J 0
(-6250 4900);
DISPLAY 1.021277 (-6250 4900);
DISPLAY INVISIBLE (-6250 4900);
FORCEADD RESISTOR..2
R 3
(-6350 4650);
FORCEPROP 0 LAST PACKAGE 0402
J 0
(-6400 4550);
DISPLAY 1.021277 (-6400 4550);
FORCEPROP 1 LAST VALUE 49.9OHM
J 2
(-5650 4650);
DISPLAY 1.212766 (-5650 4650);
PAINT GREEN (-5650 4650);
FORCEPROP 1 LAST CLS_PN G155-149R9-01
R 1
J 2
(-6550 4786);
DISPLAY 1.212766 (-6550 4786);
PAINT GREEN (-6550 4786);
DISPLAY INVISIBLE (-6550 4786);
FORCEPROP 1 LAST TOLERANCE 1%
R 1
J 2
(-6605 4847);
DISPLAY 1.212766 (-6605 4847);
PAINT GREEN (-6605 4847);
DISPLAY INVISIBLE (-6605 4847);
FORCEPROP 1 LAST PATH I258
R 1
J 2
(-6455 4847);
DISPLAY 1.212766 (-6455 4847);
PAINT GREEN (-6455 4847);
DISPLAY INVISIBLE (-6455 4847);
FORCEPROP 2 LAST CDS_LIB passive
J 0
(-6350 4650);
DISPLAY INVISIBLE (-6350 4650);
FORCEPROP 1 LAST CDS_LMAN_SYM_OUTLINE -50,50,50,-100
R 1
J 2
(-6350 4650);
DISPLAY 0.468085 (-6350 4650);
PAINT GREEN (-6350 4650);
DISPLAY INVISIBLE (-6350 4650);
FORCEPROP 1 LAST LOCATION R371
J 2
(-6550 4650);
DISPLAY 1.212766 (-6550 4650);
PAINT GREEN (-6550 4650);
FORCEPROP 0 LASTPIN (-6450 4650) $PN 1
J 2
(-6460 4660);
DISPLAY 0.680851 (-6460 4660);
PAINT MONO (-6460 4660);
FORCEPROP 0 LASTPIN (-6200 4650) $PN 2
J 0
(-6190 4660);
DISPLAY 0.680851 (-6190 4660);
PAINT MONO (-6190 4660);
FORCEPROP 0 LAST $SEC 1
R 1
J 0
(-5800 4800);
DISPLAY 0.680851 (-5800 4800);
PAINT MONO (-5800 4800);
DISPLAY INVISIBLE (-5800 4800);
FORCEPROP 0 LAST CDS_SEC 1
R 1
J 0
(-5800 4800);
DISPLAY 1.021277 (-5800 4800);
DISPLAY INVISIBLE (-5800 4800);
FORCEADD VCC..1
(-8450 5000);
FORCEPROP 3 LASTPIN (-8400 4950) SIG_NAME XP3R3V_FPGA\g
J 0
(-8390 4960);
DISPLAY 0.659574 (-8390 4960);
PAINT MONO (-8390 4960);
DISPLAY INVISIBLE (-8390 4960);
FORCEPROP 0 LAST VOLTAGE 3.3V
J 0
(-8700 5150);
DISPLAY 1.021277 (-8700 5150);
DISPLAY BOTH (-8700 5150);
FORCEPROP 1 LAST HDL_POWER XP3R3V_FPGA
J 1
(-8395 5055);
DISPLAY 1.021277 (-8395 5055);
PAINT GREEN (-8395 5055);
FORCEPROP 1 LAST PATH I259
J 0
(-8415 5090);
DISPLAY 0.808511 (-8415 5090);
PAINT GREEN (-8415 5090);
DISPLAY INVISIBLE (-8415 5090);
FORCEPROP 1 LAST BODY_TYPE PLUMBING
J 0
(-8495 4957);
DISPLAY 0.340426 (-8495 4957);
PAINT GREEN (-8495 4957);
DISPLAY INVISIBLE (-8495 4957);
FORCEPROP 1 LAST CDS_LMAN_SYM_OUTLINE -250,250,250,-250
J 0
(-8450 5000);
DISPLAY 0.468085 (-8450 5000);
PAINT GREEN (-8450 5000);
DISPLAY INVISIBLE (-8450 5000);
FORCEPROP 2 LAST CDS_LIB cls
J 0
(-8450 5000);
DISPLAY INVISIBLE (-8450 5000);
FORCEADD RESISTOR..2
R 1
(-10700 5200);
FORCEPROP 0 LAST PACKAGE 0402
J 0
(-10750 5250);
DISPLAY 1.021277 (-10750 5250);
FORCEPROP 1 LAST VALUE 4.7KOHM
J 0
(-10450 5200);
DISPLAY 1.212766 (-10450 5200);
PAINT GREEN (-10450 5200);
FORCEPROP 1 LAST PATH I261
R 1
J 0
(-10805 5003);
DISPLAY 1.212766 (-10805 5003);
PAINT GREEN (-10805 5003);
DISPLAY INVISIBLE (-10805 5003);
FORCEPROP 2 LAST CDS_LIB passive
J 0
(-10700 5200);
DISPLAY INVISIBLE (-10700 5200);
FORCEPROP 1 LAST CDS_LMAN_SYM_OUTLINE -50,50,50,-100
R 1
J 0
(-10700 5200);
DISPLAY 0.468085 (-10700 5200);
PAINT GREEN (-10700 5200);
DISPLAY INVISIBLE (-10700 5200);
FORCEPROP 1 LAST CLS_PN G155-14701-01
R 1
J 0
(-10900 5064);
DISPLAY 1.212766 (-10900 5064);
PAINT GREEN (-10900 5064);
DISPLAY INVISIBLE (-10900 5064);
FORCEPROP 1 LAST TOLERANCE 1%
R 1
J 0
(-10955 5003);
DISPLAY 1.212766 (-10955 5003);
PAINT GREEN (-10955 5003);
DISPLAY INVISIBLE (-10955 5003);
FORCEPROP 1 LAST LOCATION R361
J 0
(-11100 5200);
DISPLAY 1.212766 (-11100 5200);
PAINT GREEN (-11100 5200);
FORCEPROP 0 LASTPIN (-10800 5200) $PN 1
J 2
(-10810 5210);
DISPLAY 0.680851 (-10810 5210);
PAINT MONO (-10810 5210);
FORCEPROP 0 LASTPIN (-10550 5200) $PN 2
J 0
(-10540 5210);
DISPLAY 0.680851 (-10540 5210);
PAINT MONO (-10540 5210);
FORCEPROP 0 LAST $SEC 1
R 1
J 0
(-10500 5300);
DISPLAY 0.680851 (-10500 5300);
PAINT MONO (-10500 5300);
DISPLAY INVISIBLE (-10500 5300);
FORCEPROP 0 LAST CDS_SEC 1
R 1
J 0
(-10500 5300);
DISPLAY 1.021277 (-10500 5300);
DISPLAY INVISIBLE (-10500 5300);
FORCEADD RESISTOR..2
R 1
(-10700 5100);
FORCEPROP 0 LAST PACKAGE 0402
J 0
(-10750 5000);
DISPLAY 1.021277 (-10750 5000);
FORCEPROP 1 LAST VALUE 4.7KOHM
J 0
(-10450 5100);
DISPLAY 1.212766 (-10450 5100);
PAINT GREEN (-10450 5100);
FORCEPROP 1 LAST PATH I262
R 1
J 0
(-10805 4903);
DISPLAY 1.212766 (-10805 4903);
PAINT GREEN (-10805 4903);
DISPLAY INVISIBLE (-10805 4903);
FORCEPROP 2 LAST CDS_LIB passive
J 0
(-10700 5100);
DISPLAY INVISIBLE (-10700 5100);
FORCEPROP 1 LAST CDS_LMAN_SYM_OUTLINE -50,50,50,-100
R 1
J 0
(-10700 5100);
DISPLAY 0.468085 (-10700 5100);
PAINT GREEN (-10700 5100);
DISPLAY INVISIBLE (-10700 5100);
FORCEPROP 1 LAST CLS_PN G155-14701-01
R 1
J 0
(-10900 4964);
DISPLAY 1.212766 (-10900 4964);
PAINT GREEN (-10900 4964);
DISPLAY INVISIBLE (-10900 4964);
FORCEPROP 1 LAST TOLERANCE 1%
R 1
J 0
(-10955 4903);
DISPLAY 1.212766 (-10955 4903);
PAINT GREEN (-10955 4903);
DISPLAY INVISIBLE (-10955 4903);
FORCEPROP 1 LAST LOCATION R381
J 0
(-11100 5100);
DISPLAY 1.212766 (-11100 5100);
PAINT GREEN (-11100 5100);
FORCEPROP 0 LASTPIN (-10800 5100) $PN 1
J 2
(-10810 5110);
DISPLAY 0.680851 (-10810 5110);
PAINT MONO (-10810 5110);
FORCEPROP 0 LASTPIN (-10550 5100) $PN 2
J 0
(-10540 5110);
DISPLAY 0.680851 (-10540 5110);
PAINT MONO (-10540 5110);
FORCEPROP 0 LAST $SEC 1
R 1
J 0
(-10500 5250);
DISPLAY 0.680851 (-10500 5250);
PAINT MONO (-10500 5250);
DISPLAY INVISIBLE (-10500 5250);
FORCEPROP 0 LAST CDS_SEC 1
R 1
J 0
(-10500 5250);
DISPLAY 1.021277 (-10500 5250);
DISPLAY INVISIBLE (-10500 5250);
FORCEADD VCC..1
(-11350 5350);
FORCEPROP 3 LASTPIN (-11300 5300) SIG_NAME XP3R3V_FPGA\g
J 0
(-11290 5310);
DISPLAY 0.659574 (-11290 5310);
PAINT MONO (-11290 5310);
DISPLAY INVISIBLE (-11290 5310);
FORCEPROP 0 LAST VOLTAGE 3.3V
J 0
(-11600 5500);
DISPLAY 1.021277 (-11600 5500);
DISPLAY BOTH (-11600 5500);
FORCEPROP 1 LAST HDL_POWER XP3R3V_FPGA
J 1
(-11295 5405);
DISPLAY 1.021277 (-11295 5405);
PAINT GREEN (-11295 5405);
FORCEPROP 1 LAST PATH I264
J 0
(-11315 5440);
DISPLAY 0.808511 (-11315 5440);
PAINT GREEN (-11315 5440);
DISPLAY INVISIBLE (-11315 5440);
FORCEPROP 1 LAST BODY_TYPE PLUMBING
J 0
(-11395 5307);
DISPLAY 0.340426 (-11395 5307);
PAINT GREEN (-11395 5307);
DISPLAY INVISIBLE (-11395 5307);
FORCEPROP 1 LAST CDS_LMAN_SYM_OUTLINE -250,250,250,-250
J 0
(-11350 5350);
DISPLAY 0.468085 (-11350 5350);
PAINT GREEN (-11350 5350);
DISPLAY INVISIBLE (-11350 5350);
FORCEPROP 2 LAST CDS_LIB cls
J 0
(-11350 5350);
DISPLAY INVISIBLE (-11350 5350);
FORCEADD RESISTOR..2
R 3
(-10700 4750);
FORCEPROP 0 LAST PACKAGE 0402
J 0
(-10750 4800);
DISPLAY 0.808511 (-10750 4800);
FORCEPROP 1 LAST VALUE 100OHM
J 2
(-10100 4750);
DISPLAY 1.212766 (-10100 4750);
PAINT GREEN (-10100 4750);
FORCEPROP 1 LAST CLS_PN G155-11000-01
R 1
J 2
(-10900 4886);
DISPLAY 1.212766 (-10900 4886);
PAINT GREEN (-10900 4886);
DISPLAY INVISIBLE (-10900 4886);
FORCEPROP 1 LAST TOLERANCE 1%
R 1
J 2
(-10955 4947);
DISPLAY 1.212766 (-10955 4947);
PAINT GREEN (-10955 4947);
DISPLAY INVISIBLE (-10955 4947);
FORCEPROP 2 LAST CDS_LIB passive
J 0
(-10700 4750);
DISPLAY INVISIBLE (-10700 4750);
FORCEPROP 1 LAST CDS_LMAN_SYM_OUTLINE -50,50,50,-100
R 1
J 2
(-10700 4750);
DISPLAY 0.468085 (-10700 4750);
PAINT GREEN (-10700 4750);
DISPLAY INVISIBLE (-10700 4750);
FORCEPROP 1 LAST PATH I265
R 1
J 2
(-10805 4947);
DISPLAY 1.212766 (-10805 4947);
PAINT GREEN (-10805 4947);
DISPLAY INVISIBLE (-10805 4947);
FORCEPROP 1 LAST LOCATION R120
J 2
(-10850 4750);
DISPLAY 1.212766 (-10850 4750);
PAINT GREEN (-10850 4750);
FORCEPROP 0 LASTPIN (-10800 4750) $PN 1
J 2
(-10810 4760);
DISPLAY 0.680851 (-10810 4760);
PAINT MONO (-10810 4760);
FORCEPROP 0 LASTPIN (-10550 4750) $PN 2
J 0
(-10540 4760);
DISPLAY 0.680851 (-10540 4760);
PAINT MONO (-10540 4760);
FORCEPROP 0 LAST $SEC 1
R 1
J 0
(-10150 4900);
DISPLAY 0.680851 (-10150 4900);
PAINT MONO (-10150 4900);
DISPLAY INVISIBLE (-10150 4900);
FORCEPROP 0 LAST CDS_SEC 1
R 1
J 0
(-10150 4900);
DISPLAY 1.021277 (-10150 4900);
DISPLAY INVISIBLE (-10150 4900);
FORCEADD OFFPAGE_IN..1
R 6
(-12950 4850);
FORCEPROP 2 LAST $XR0 12G5> 
J 0
(-13133 4850);
DISPLAY 0.638298 (-13133 4850);
PAINT MONO (-13133 4850);
FORCEPROP 2 LAST $XR1 25E6<> 
J 0
(-13343 4850);
DISPLAY 0.638298 (-13343 4850);
PAINT MONO (-13343 4850);
FORCEPROP 2 LAST CDS_LIB cls
J 0
(-12950 4850);
DISPLAY INVISIBLE (-12950 4850);
FORCEPROP 1 LAST CDS_LMAN_SYM_OUTLINE -50,50,50,-50
J 0
(-12950 4850);
DISPLAY 0.468085 (-12950 4850);
PAINT GREEN (-12950 4850);
DISPLAY INVISIBLE (-12950 4850);
FORCEPROP 1 LAST BODY_TYPE COMMENT
J 0
(-12940 4715);
DISPLAY 0.808511 (-12940 4715);
PAINT GREEN (-12940 4715);
DISPLAY INVISIBLE (-12940 4715);
FORCEPROP 1 LAST OFFPAGE TRUE
J 0
(-12940 4795);
DISPLAY 0.808511 (-12940 4795);
PAINT GREEN (-12940 4795);
DISPLAY INVISIBLE (-12940 4795);
FORCEPROP 2 LAST PATH I267
J 0
(-13100 4900);
DISPLAY 1.021277 (-13100 4900);
DISPLAY INVISIBLE (-13100 4900);
FORCEADD OFFPAGE_IN..1
R 6
(-12950 4750);
FORCEPROP 2 LAST $XR0 11E5> 
J 0
(-13133 4750);
DISPLAY 0.638298 (-13133 4750);
PAINT MONO (-13133 4750);
FORCEPROP 1 LAST BODY_TYPE COMMENT
J 0
(-12940 4615);
DISPLAY 0.808511 (-12940 4615);
PAINT GREEN (-12940 4615);
DISPLAY INVISIBLE (-12940 4615);
FORCEPROP 1 LAST CDS_LMAN_SYM_OUTLINE -50,50,50,-50
J 0
(-12950 4750);
DISPLAY 0.468085 (-12950 4750);
PAINT GREEN (-12950 4750);
DISPLAY INVISIBLE (-12950 4750);
FORCEPROP 2 LAST CDS_LIB cls
J 0
(-12950 4750);
DISPLAY INVISIBLE (-12950 4750);
FORCEPROP 1 LAST OFFPAGE TRUE
J 0
(-12940 4695);
DISPLAY 0.808511 (-12940 4695);
PAINT GREEN (-12940 4695);
DISPLAY INVISIBLE (-12940 4695);
FORCEPROP 2 LAST PATH I268
J 0
(-13100 4800);
DISPLAY 1.021277 (-13100 4800);
DISPLAY INVISIBLE (-13100 4800);
FORCEADD OFFPAGE_IN..1
R 6
(-12950 4550);
FORCEPROP 2 LAST $XR0 12G5> 
J 0
(-13133 4550);
DISPLAY 0.638298 (-13133 4550);
PAINT MONO (-13133 4550);
FORCEPROP 2 LAST $XR1 25E6<> 
J 0
(-13343 4550);
DISPLAY 0.638298 (-13343 4550);
PAINT MONO (-13343 4550);
FORCEPROP 2 LAST CDS_LIB cls
J 0
(-12950 4550);
DISPLAY INVISIBLE (-12950 4550);
FORCEPROP 1 LAST CDS_LMAN_SYM_OUTLINE -50,50,50,-50
J 0
(-12950 4550);
DISPLAY 0.468085 (-12950 4550);
PAINT GREEN (-12950 4550);
DISPLAY INVISIBLE (-12950 4550);
FORCEPROP 1 LAST BODY_TYPE COMMENT
J 0
(-12940 4415);
DISPLAY 0.808511 (-12940 4415);
PAINT GREEN (-12940 4415);
DISPLAY INVISIBLE (-12940 4415);
FORCEPROP 1 LAST OFFPAGE TRUE
J 0
(-12940 4495);
DISPLAY 0.808511 (-12940 4495);
PAINT GREEN (-12940 4495);
DISPLAY INVISIBLE (-12940 4495);
FORCEPROP 2 LAST PATH I269
J 0
(-12900 4650);
DISPLAY 1.021277 (-12900 4650);
DISPLAY INVISIBLE (-12900 4650);
FORCEADD GND_SG..1
(-8750 4100);
FORCEPROP 3 LASTPIN (-8700 4150) SIG_NAME SG\g
J 0
(-8690 4160);
DISPLAY 0.659574 (-8690 4160);
PAINT MONO (-8690 4160);
DISPLAY INVISIBLE (-8690 4160);
FORCEPROP 1 LAST HDL_POWER SG
J 1
(-8700 4000);
DISPLAY 0.808511 (-8700 4000);
PAINT GREEN (-8700 4000);
FORCEPROP 1 LAST PATH I271
J 0
(-8715 4100);
DISPLAY 0.808511 (-8715 4100);
PAINT GREEN (-8715 4100);
DISPLAY INVISIBLE (-8715 4100);
FORCEPROP 1 LAST BODY_TYPE PLUMBING
J 0
(-8735 4085);
DISPLAY 0.808511 (-8735 4085);
PAINT GREEN (-8735 4085);
DISPLAY INVISIBLE (-8735 4085);
FORCEPROP 2 LAST CDS_LIB cls
J 0
(-8750 4100);
DISPLAY INVISIBLE (-8750 4100);
FORCEPROP 1 LAST CDS_LMAN_SYM_OUTLINE 0,0,100,-50
J 0
(-8750 4100);
DISPLAY 0.468085 (-8750 4100);
PAINT GREEN (-8750 4100);
DISPLAY INVISIBLE (-8750 4100);
FORCEADD CAPACITOR..2
(-8400 4450);
FORCEPROP 0 LAST PACKAGE 0402
J 0
(-8300 4400);
DISPLAY 1.021277 (-8300 4400);
FORCEPROP 1 LAST VALUE 0.1UF
J 0
(-8350 4500);
DISPLAY 1.212766 (-8350 4500);
PAINT GREEN (-8350 4500);
FORCEPROP 0 LAST VOLTAGE 10V
J 0
(-8350 4200);
DISPLAY 1.021277 (-8350 4200);
FORCEPROP 1 LAST PATH I272
J 0
(-8500 4500);
DISPLAY 1.212766 (-8500 4500);
PAINT GREEN (-8500 4500);
DISPLAY INVISIBLE (-8500 4500);
FORCEPROP 1 LAST TOLERANCE 10%
J 0
(-8550 4550);
DISPLAY 1.212766 (-8550 4550);
PAINT GREEN (-8550 4550);
DISPLAY INVISIBLE (-8550 4550);
FORCEPROP 1 LAST CLS_PN G105-0B104-CK
J 0
(-8500 4500);
DISPLAY 1.212766 (-8500 4500);
PAINT GREEN (-8500 4500);
DISPLAY INVISIBLE (-8500 4500);
FORCEPROP 1 LAST CDS_LMAN_SYM_OUTLINE -50,0,50,-50
J 0
(-8400 4450);
DISPLAY 0.468085 (-8400 4450);
PAINT GREEN (-8400 4450);
DISPLAY INVISIBLE (-8400 4450);
FORCEPROP 2 LAST CDS_LIB passive
J 0
(-8400 4450);
DISPLAY INVISIBLE (-8400 4450);
FORCEPROP 1 LAST $LOCATION C85
J 0
(-8350 4300);
DISPLAY 1.212766 (-8350 4300);
PAINT GREEN (-8350 4300);
FORCEPROP 0 LASTPIN (-8400 4550) $PN 1
R 1
J 0
(-8410 4560);
DISPLAY 0.680851 (-8410 4560);
PAINT MONO (-8410 4560);
FORCEPROP 0 LASTPIN (-8400 4300) $PN 2
R 1
J 2
(-8410 4290);
DISPLAY 0.680851 (-8410 4290);
PAINT MONO (-8410 4290);
FORCEPROP 0 LAST CDS_LOCATION C85
J 0
(-8350 4600);
DISPLAY 1.021277 (-8350 4600);
DISPLAY INVISIBLE (-8350 4600);
FORCEPROP 0 LAST $SEC 1
J 0
(-8350 4600);
DISPLAY 0.680851 (-8350 4600);
PAINT MONO (-8350 4600);
DISPLAY INVISIBLE (-8350 4600);
FORCEPROP 0 LAST CDS_SEC 1
J 0
(-8350 4600);
DISPLAY 1.021277 (-8350 4600);
DISPLAY INVISIBLE (-8350 4600);
FORCEADD 74HCT2G125DP_TSSOP8..1
(-9450 2800);
FORCEPROP 0 LAST VALUE NC7WV125K8X
J 0
(-9450 3100);
FORCEPROP 1 LAST CLS_PN G220-00055-01
J 0
(-9450 2950);
DISPLAY 1.212766 (-9450 2950);
PAINT GREEN (-9450 2950);
FORCEPROP 1 LAST PATH I273
J 0
(-9400 2850);
DISPLAY 1.212766 (-9400 2850);
PAINT GREEN (-9400 2850);
DISPLAY INVISIBLE (-9400 2850);
FORCEPROP 2 LASTPIN (-9550 2600) SIG_NAME UN$12$74HCT2G125DPTSSOP8$I273$1A
J 0
(-9540 2610);
DISPLAY 0.659574 (-9540 2610);
PAINT MONO (-9540 2610);
DISPLAY INVISIBLE (-9540 2610);
FORCEPROP 2 LAST CDS_LIB stdlogic
J 0
(-9450 2800);
DISPLAY INVISIBLE (-9450 2800);
FORCEPROP 1 LAST CDS_LMAN_SYM_OUTLINE 0,0,500,-500
J 0
(-9450 2800);
DISPLAY 0.468085 (-9450 2800);
PAINT GREEN (-9450 2800);
DISPLAY INVISIBLE (-9450 2800);
FORCEPROP 1 LAST LOCATION U16
J 0
(-9450 2850);
DISPLAY 1.212766 (-9450 2850);
PAINT GREEN (-9450 2850);
FORCEPROP 0 LASTPIN (-9550 2600) $PN 2
J 2
(-9560 2610);
DISPLAY 0.680851 (-9560 2610);
PAINT MONO (-9560 2610);
FORCEPROP 0 LASTPIN (-9550 2700) $PN 1
J 2
(-9560 2710);
DISPLAY 0.680851 (-9560 2710);
PAINT MONO (-9560 2710);
FORCEPROP 0 LASTPIN (-8850 2600) $PN 6
J 0
(-8840 2610);
DISPLAY 0.680851 (-8840 2610);
PAINT MONO (-8840 2610);
FORCEPROP 0 LASTPIN (-9550 2500) $PN 5
J 2
(-9560 2510);
DISPLAY 0.680851 (-9560 2510);
PAINT MONO (-9560 2510);
FORCEPROP 0 LASTPIN (-9550 2400) $PN 7
J 2
(-9560 2410);
DISPLAY 0.680851 (-9560 2410);
PAINT MONO (-9560 2410);
FORCEPROP 0 LASTPIN (-8850 2500) $PN 3
J 0
(-8840 2510);
DISPLAY 0.680851 (-8840 2510);
PAINT MONO (-8840 2510);
FORCEPROP 0 LASTPIN (-8850 2400) $PN 4
J 0
(-8840 2410);
DISPLAY 0.680851 (-8840 2410);
PAINT MONO (-8840 2410);
FORCEPROP 0 LASTPIN (-8850 2700) $PN 8
J 0
(-8840 2710);
DISPLAY 0.680851 (-8840 2710);
PAINT MONO (-8840 2710);
FORCEPROP 0 LAST $SEC 1
J 0
(-9450 3150);
DISPLAY 0.680851 (-9450 3150);
PAINT MONO (-9450 3150);
DISPLAY INVISIBLE (-9450 3150);
FORCEPROP 0 LAST CDS_SEC 1
J 0
(-9450 3150);
DISPLAY 1.021277 (-9450 3150);
DISPLAY INVISIBLE (-9450 3150);
FORCEADD OFFPAGE_OUT..1
(-4800 2500);
FORCEPROP 2 LAST $XR0 11E12< 
J 0
(-4745 2500);
DISPLAY 0.638298 (-4745 2500);
PAINT MONO (-4745 2500);
FORCEPROP 2 LAST $XR1 ?
J 0
(-4535 2500);
DISPLAY 0.638298 (-4535 2500);
PAINT MONO (-4535 2500);
FORCEPROP 2 LAST PATH I274
J 0
(-4750 2600);
DISPLAY 1.021277 (-4750 2600);
DISPLAY INVISIBLE (-4750 2600);
FORCEPROP 1 LAST OFFPAGE TRUE
J 0
(-4790 2555);
DISPLAY 0.808511 (-4790 2555);
PAINT GREEN (-4790 2555);
DISPLAY INVISIBLE (-4790 2555);
FORCEPROP 1 LAST BODY_TYPE COMMENT
J 0
(-4790 2635);
DISPLAY 0.808511 (-4790 2635);
PAINT GREEN (-4790 2635);
DISPLAY INVISIBLE (-4790 2635);
FORCEPROP 1 LAST CDS_LMAN_SYM_OUTLINE -50,50,50,-50
J 0
(-4800 2500);
DISPLAY 0.468085 (-4800 2500);
PAINT GREEN (-4800 2500);
DISPLAY INVISIBLE (-4800 2500);
FORCEPROP 2 LAST CDS_LIB cls
J 2
(-4800 2500);
DISPLAY INVISIBLE (-4800 2500);
FORCEADD RESISTOR..2
R 3
(-6300 2500);
FORCEPROP 1 LAST VALUE 49.9OHM
J 2
(-5600 2500);
DISPLAY 1.212766 (-5600 2500);
PAINT GREEN (-5600 2500);
FORCEPROP 0 LAST PACKAGE 0402
J 0
(-6350 2400);
DISPLAY 1.021277 (-6350 2400);
FORCEPROP 1 LAST PATH I275
R 1
J 2
(-6405 2697);
DISPLAY 1.212766 (-6405 2697);
PAINT GREEN (-6405 2697);
DISPLAY INVISIBLE (-6405 2697);
FORCEPROP 1 LAST CDS_LMAN_SYM_OUTLINE -50,50,50,-100
R 1
J 2
(-6300 2500);
DISPLAY 0.468085 (-6300 2500);
PAINT GREEN (-6300 2500);
DISPLAY INVISIBLE (-6300 2500);
FORCEPROP 2 LAST CDS_LIB passive
J 0
(-6300 2500);
DISPLAY INVISIBLE (-6300 2500);
FORCEPROP 1 LAST TOLERANCE 1%
R 1
J 2
(-6555 2697);
DISPLAY 1.212766 (-6555 2697);
PAINT GREEN (-6555 2697);
DISPLAY INVISIBLE (-6555 2697);
FORCEPROP 1 LAST CLS_PN G155-149R9-01
R 1
J 2
(-6500 2636);
DISPLAY 1.212766 (-6500 2636);
PAINT GREEN (-6500 2636);
DISPLAY INVISIBLE (-6500 2636);
FORCEPROP 1 LAST LOCATION R372
J 2
(-6500 2500);
DISPLAY 1.212766 (-6500 2500);
PAINT GREEN (-6500 2500);
FORCEPROP 0 LASTPIN (-6400 2500) $PN 1
J 2
(-6410 2510);
DISPLAY 0.680851 (-6410 2510);
PAINT MONO (-6410 2510);
FORCEPROP 0 LASTPIN (-6150 2500) $PN 2
J 0
(-6140 2510);
DISPLAY 0.680851 (-6140 2510);
PAINT MONO (-6140 2510);
FORCEPROP 0 LAST $SEC 1
R 1
J 0
(-5750 2650);
DISPLAY 0.680851 (-5750 2650);
PAINT MONO (-5750 2650);
DISPLAY INVISIBLE (-5750 2650);
FORCEPROP 0 LAST CDS_SEC 1
R 1
J 0
(-5750 2650);
DISPLAY 1.021277 (-5750 2650);
DISPLAY INVISIBLE (-5750 2650);
FORCEADD RESISTOR..2
R 3
(-6300 2600);
FORCEPROP 0 LAST PACKAGE 0402
J 0
(-6350 2650);
DISPLAY 1.021277 (-6350 2650);
FORCEPROP 1 LAST VALUE 49.9OHM
J 2
(-5600 2600);
DISPLAY 1.212766 (-5600 2600);
PAINT GREEN (-5600 2600);
FORCEPROP 1 LAST PATH I276
R 1
J 2
(-6405 2797);
DISPLAY 1.212766 (-6405 2797);
PAINT GREEN (-6405 2797);
DISPLAY INVISIBLE (-6405 2797);
FORCEPROP 2 LAST CDS_LIB passive
R 1
J 0
(-6300 2600);
DISPLAY INVISIBLE (-6300 2600);
FORCEPROP 1 LAST CDS_LMAN_SYM_OUTLINE -50,50,50,-100
R 1
J 2
(-6300 2600);
DISPLAY 0.468085 (-6300 2600);
PAINT GREEN (-6300 2600);
DISPLAY INVISIBLE (-6300 2600);
FORCEPROP 1 LAST TOLERANCE 1%
R 1
J 2
(-6555 2797);
DISPLAY 1.212766 (-6555 2797);
PAINT GREEN (-6555 2797);
DISPLAY INVISIBLE (-6555 2797);
FORCEPROP 1 LAST CLS_PN G155-149R9-01
R 1
J 2
(-6500 2736);
DISPLAY 1.212766 (-6500 2736);
PAINT GREEN (-6500 2736);
DISPLAY INVISIBLE (-6500 2736);
FORCEPROP 1 LAST LOCATION R126
J 2
(-6500 2600);
DISPLAY 1.212766 (-6500 2600);
PAINT GREEN (-6500 2600);
FORCEPROP 0 LASTPIN (-6400 2600) $PN 1
J 2
(-6410 2610);
DISPLAY 0.680851 (-6410 2610);
PAINT MONO (-6410 2610);
FORCEPROP 0 LASTPIN (-6150 2600) $PN 2
J 0
(-6140 2610);
DISPLAY 0.680851 (-6140 2610);
PAINT MONO (-6140 2610);
FORCEPROP 0 LAST $SEC 1
R 1
J 0
(-6200 2750);
DISPLAY 0.680851 (-6200 2750);
PAINT MONO (-6200 2750);
DISPLAY INVISIBLE (-6200 2750);
FORCEPROP 0 LAST CDS_SEC 1
R 1
J 0
(-6200 2750);
DISPLAY 1.021277 (-6200 2750);
DISPLAY INVISIBLE (-6200 2750);
FORCEADD VCC..1
(-8400 2850);
FORCEPROP 3 LASTPIN (-8350 2800) SIG_NAME XP3R3V_FPGA\g
J 0
(-8340 2810);
DISPLAY 0.659574 (-8340 2810);
PAINT MONO (-8340 2810);
DISPLAY INVISIBLE (-8340 2810);
FORCEPROP 1 LAST HDL_POWER XP3R3V_FPGA
J 1
(-8345 2905);
DISPLAY 1.021277 (-8345 2905);
PAINT GREEN (-8345 2905);
FORCEPROP 0 LAST VOLTAGE 3.3V
J 0
(-8650 3000);
DISPLAY 1.021277 (-8650 3000);
DISPLAY BOTH (-8650 3000);
FORCEPROP 1 LAST PATH I277
J 0
(-8365 2940);
DISPLAY 0.808511 (-8365 2940);
PAINT GREEN (-8365 2940);
DISPLAY INVISIBLE (-8365 2940);
FORCEPROP 1 LAST BODY_TYPE PLUMBING
J 0
(-8445 2807);
DISPLAY 0.340426 (-8445 2807);
PAINT GREEN (-8445 2807);
DISPLAY INVISIBLE (-8445 2807);
FORCEPROP 1 LAST CDS_LMAN_SYM_OUTLINE -250,250,250,-250
J 0
(-8400 2850);
DISPLAY 0.468085 (-8400 2850);
PAINT GREEN (-8400 2850);
DISPLAY INVISIBLE (-8400 2850);
FORCEPROP 2 LAST CDS_LIB cls
J 0
(-8400 2850);
DISPLAY INVISIBLE (-8400 2850);
FORCEADD GND_SG..1
(-8700 1950);
FORCEPROP 3 LASTPIN (-8650 2000) SIG_NAME SG\g
J 0
(-8640 2010);
DISPLAY 0.659574 (-8640 2010);
PAINT MONO (-8640 2010);
DISPLAY INVISIBLE (-8640 2010);
FORCEPROP 1 LAST HDL_POWER SG
J 1
(-8650 1850);
DISPLAY 0.808511 (-8650 1850);
PAINT GREEN (-8650 1850);
FORCEPROP 1 LAST PATH I279
J 0
(-8665 1950);
DISPLAY 0.808511 (-8665 1950);
PAINT GREEN (-8665 1950);
DISPLAY INVISIBLE (-8665 1950);
FORCEPROP 1 LAST BODY_TYPE PLUMBING
J 0
(-8685 1935);
DISPLAY 0.808511 (-8685 1935);
PAINT GREEN (-8685 1935);
DISPLAY INVISIBLE (-8685 1935);
FORCEPROP 2 LAST CDS_LIB cls
J 0
(-8700 1950);
DISPLAY INVISIBLE (-8700 1950);
FORCEPROP 1 LAST CDS_LMAN_SYM_OUTLINE 0,0,100,-50
J 0
(-8700 1950);
DISPLAY 0.468085 (-8700 1950);
PAINT GREEN (-8700 1950);
DISPLAY INVISIBLE (-8700 1950);
FORCEADD RESISTOR..2
R 1
(-10650 3050);
FORCEPROP 0 LAST PACKAGE 0402
J 0
(-10700 3100);
DISPLAY 1.021277 (-10700 3100);
FORCEPROP 1 LAST VALUE 4.7KOHM
J 0
(-10400 3050);
DISPLAY 1.212766 (-10400 3050);
PAINT GREEN (-10400 3050);
FORCEPROP 1 LAST PATH I280
R 1
J 0
(-10755 2853);
DISPLAY 1.212766 (-10755 2853);
PAINT GREEN (-10755 2853);
DISPLAY INVISIBLE (-10755 2853);
FORCEPROP 2 LAST CDS_LIB passive
J 0
(-10650 3050);
DISPLAY INVISIBLE (-10650 3050);
FORCEPROP 1 LAST CDS_LMAN_SYM_OUTLINE -50,50,50,-100
R 1
J 0
(-10650 3050);
DISPLAY 0.468085 (-10650 3050);
PAINT GREEN (-10650 3050);
DISPLAY INVISIBLE (-10650 3050);
FORCEPROP 1 LAST CLS_PN G155-14701-01
R 1
J 0
(-10850 2914);
DISPLAY 1.212766 (-10850 2914);
PAINT GREEN (-10850 2914);
DISPLAY INVISIBLE (-10850 2914);
FORCEPROP 1 LAST TOLERANCE 1%
R 1
J 0
(-10905 2853);
DISPLAY 1.212766 (-10905 2853);
PAINT GREEN (-10905 2853);
DISPLAY INVISIBLE (-10905 2853);
FORCEPROP 1 LAST LOCATION R331
J 0
(-11050 3050);
DISPLAY 1.212766 (-11050 3050);
PAINT GREEN (-11050 3050);
FORCEPROP 0 LASTPIN (-10750 3050) $PN 1
J 2
(-10760 3060);
DISPLAY 0.680851 (-10760 3060);
PAINT MONO (-10760 3060);
FORCEPROP 0 LASTPIN (-10500 3050) $PN 2
J 0
(-10490 3060);
DISPLAY 0.680851 (-10490 3060);
PAINT MONO (-10490 3060);
FORCEPROP 0 LAST $SEC 1
R 1
J 0
(-10450 3150);
DISPLAY 0.680851 (-10450 3150);
PAINT MONO (-10450 3150);
DISPLAY INVISIBLE (-10450 3150);
FORCEPROP 0 LAST CDS_SEC 1
R 1
J 0
(-10450 3150);
DISPLAY 1.021277 (-10450 3150);
DISPLAY INVISIBLE (-10450 3150);
FORCEADD RESISTOR..2
R 1
(-10650 2950);
FORCEPROP 0 LAST PACKAGE 0402
J 0
(-10700 2850);
DISPLAY 1.021277 (-10700 2850);
FORCEPROP 1 LAST VALUE 4.7KOHM
J 0
(-10400 2950);
DISPLAY 1.212766 (-10400 2950);
PAINT GREEN (-10400 2950);
FORCEPROP 1 LAST PATH I281
R 1
J 0
(-10755 2753);
DISPLAY 1.212766 (-10755 2753);
PAINT GREEN (-10755 2753);
DISPLAY INVISIBLE (-10755 2753);
FORCEPROP 2 LAST CDS_LIB passive
J 0
(-10650 2950);
DISPLAY INVISIBLE (-10650 2950);
FORCEPROP 1 LAST CDS_LMAN_SYM_OUTLINE -50,50,50,-100
R 1
J 0
(-10650 2950);
DISPLAY 0.468085 (-10650 2950);
PAINT GREEN (-10650 2950);
DISPLAY INVISIBLE (-10650 2950);
FORCEPROP 1 LAST CLS_PN G155-14701-01
R 1
J 0
(-10850 2814);
DISPLAY 1.212766 (-10850 2814);
PAINT GREEN (-10850 2814);
DISPLAY INVISIBLE (-10850 2814);
FORCEPROP 1 LAST TOLERANCE 1%
R 1
J 0
(-10905 2753);
DISPLAY 1.212766 (-10905 2753);
PAINT GREEN (-10905 2753);
DISPLAY INVISIBLE (-10905 2753);
FORCEPROP 1 LAST LOCATION R383
J 0
(-11050 2950);
DISPLAY 1.212766 (-11050 2950);
PAINT GREEN (-11050 2950);
FORCEPROP 0 LASTPIN (-10750 2950) $PN 1
J 2
(-10760 2960);
DISPLAY 0.680851 (-10760 2960);
PAINT MONO (-10760 2960);
FORCEPROP 0 LASTPIN (-10500 2950) $PN 2
J 0
(-10490 2960);
DISPLAY 0.680851 (-10490 2960);
PAINT MONO (-10490 2960);
FORCEPROP 0 LAST $SEC 1
R 1
J 0
(-10450 3100);
DISPLAY 0.680851 (-10450 3100);
PAINT MONO (-10450 3100);
DISPLAY INVISIBLE (-10450 3100);
FORCEPROP 0 LAST CDS_SEC 1
R 1
J 0
(-10450 3100);
DISPLAY 1.021277 (-10450 3100);
DISPLAY INVISIBLE (-10450 3100);
FORCEADD VCC..1
(-11300 3200);
FORCEPROP 3 LASTPIN (-11250 3150) SIG_NAME XP3R3V_FPGA\g
J 0
(-11240 3160);
DISPLAY 0.659574 (-11240 3160);
PAINT MONO (-11240 3160);
DISPLAY INVISIBLE (-11240 3160);
FORCEPROP 1 LAST HDL_POWER XP3R3V_FPGA
J 1
(-11245 3255);
DISPLAY 1.021277 (-11245 3255);
PAINT GREEN (-11245 3255);
FORCEPROP 0 LAST VOLTAGE 3.3V
J 0
(-11550 3350);
DISPLAY 1.021277 (-11550 3350);
DISPLAY BOTH (-11550 3350);
FORCEPROP 1 LAST PATH I282
J 0
(-11265 3290);
DISPLAY 0.808511 (-11265 3290);
PAINT GREEN (-11265 3290);
DISPLAY INVISIBLE (-11265 3290);
FORCEPROP 1 LAST BODY_TYPE PLUMBING
J 0
(-11345 3157);
DISPLAY 0.340426 (-11345 3157);
PAINT GREEN (-11345 3157);
DISPLAY INVISIBLE (-11345 3157);
FORCEPROP 1 LAST CDS_LMAN_SYM_OUTLINE -250,250,250,-250
J 0
(-11300 3200);
DISPLAY 0.468085 (-11300 3200);
PAINT GREEN (-11300 3200);
DISPLAY INVISIBLE (-11300 3200);
FORCEPROP 2 LAST CDS_LIB cls
J 0
(-11300 3200);
DISPLAY INVISIBLE (-11300 3200);
FORCEADD RESISTOR..2
R 3
(-10650 2600);
FORCEPROP 1 LAST VALUE 100OHM
J 2
(-10050 2600);
DISPLAY 1.212766 (-10050 2600);
PAINT GREEN (-10050 2600);
FORCEPROP 0 LAST PACKAGE 0402
J 0
(-10700 2650);
DISPLAY 0.808511 (-10700 2650);
FORCEPROP 1 LAST CLS_PN G155-11000-01
R 1
J 2
(-10850 2736);
DISPLAY 1.212766 (-10850 2736);
PAINT GREEN (-10850 2736);
DISPLAY INVISIBLE (-10850 2736);
FORCEPROP 1 LAST TOLERANCE 1%
R 1
J 2
(-10905 2797);
DISPLAY 1.212766 (-10905 2797);
PAINT GREEN (-10905 2797);
DISPLAY INVISIBLE (-10905 2797);
FORCEPROP 2 LAST CDS_LIB passive
J 0
(-10650 2600);
DISPLAY INVISIBLE (-10650 2600);
FORCEPROP 1 LAST CDS_LMAN_SYM_OUTLINE -50,50,50,-100
R 1
J 2
(-10650 2600);
DISPLAY 0.468085 (-10650 2600);
PAINT GREEN (-10650 2600);
DISPLAY INVISIBLE (-10650 2600);
FORCEPROP 1 LAST PATH I284
R 1
J 2
(-10755 2797);
DISPLAY 1.212766 (-10755 2797);
PAINT GREEN (-10755 2797);
DISPLAY INVISIBLE (-10755 2797);
FORCEPROP 1 LAST LOCATION R121
J 2
(-10800 2600);
DISPLAY 1.212766 (-10800 2600);
PAINT GREEN (-10800 2600);
FORCEPROP 0 LASTPIN (-10750 2600) $PN 1
J 2
(-10760 2610);
DISPLAY 0.680851 (-10760 2610);
PAINT MONO (-10760 2610);
FORCEPROP 0 LASTPIN (-10500 2600) $PN 2
J 0
(-10490 2610);
DISPLAY 0.680851 (-10490 2610);
PAINT MONO (-10490 2610);
FORCEPROP 0 LAST $SEC 1
R 1
J 0
(-10100 2750);
DISPLAY 0.680851 (-10100 2750);
PAINT MONO (-10100 2750);
DISPLAY INVISIBLE (-10100 2750);
FORCEPROP 0 LAST CDS_SEC 1
R 1
J 0
(-10100 2750);
DISPLAY 1.021277 (-10100 2750);
DISPLAY INVISIBLE (-10100 2750);
FORCEADD OFFPAGE_IN..1
R 6
(-12950 2700);
FORCEPROP 2 LAST $XR0 12G5> 
J 0
(-13133 2700);
DISPLAY 0.638298 (-13133 2700);
PAINT MONO (-13133 2700);
FORCEPROP 2 LAST $XR1 25E6<> 
J 0
(-13343 2700);
DISPLAY 0.638298 (-13343 2700);
PAINT MONO (-13343 2700);
FORCEPROP 2 LAST CDS_LIB cls
J 0
(-12950 2700);
DISPLAY INVISIBLE (-12950 2700);
FORCEPROP 1 LAST CDS_LMAN_SYM_OUTLINE -50,50,50,-50
J 0
(-12950 2700);
DISPLAY 0.468085 (-12950 2700);
PAINT GREEN (-12950 2700);
DISPLAY INVISIBLE (-12950 2700);
FORCEPROP 1 LAST BODY_TYPE COMMENT
J 0
(-12940 2565);
DISPLAY 0.808511 (-12940 2565);
PAINT GREEN (-12940 2565);
DISPLAY INVISIBLE (-12940 2565);
FORCEPROP 1 LAST OFFPAGE TRUE
J 0
(-12940 2645);
DISPLAY 0.808511 (-12940 2645);
PAINT GREEN (-12940 2645);
DISPLAY INVISIBLE (-12940 2645);
FORCEPROP 2 LAST PATH I286
J 0
(-13100 2750);
DISPLAY 1.021277 (-13100 2750);
DISPLAY INVISIBLE (-13100 2750);
FORCEADD OFFPAGE_IN..1
R 6
(-12950 2600);
FORCEPROP 2 LAST $XR0 11E5> 
J 0
(-13133 2600);
DISPLAY 0.638298 (-13133 2600);
PAINT MONO (-13133 2600);
FORCEPROP 1 LAST BODY_TYPE COMMENT
J 0
(-12940 2465);
DISPLAY 0.808511 (-12940 2465);
PAINT GREEN (-12940 2465);
DISPLAY INVISIBLE (-12940 2465);
FORCEPROP 1 LAST CDS_LMAN_SYM_OUTLINE -50,50,50,-50
J 0
(-12950 2600);
DISPLAY 0.468085 (-12950 2600);
PAINT GREEN (-12950 2600);
DISPLAY INVISIBLE (-12950 2600);
FORCEPROP 2 LAST CDS_LIB cls
J 0
(-12950 2600);
DISPLAY INVISIBLE (-12950 2600);
FORCEPROP 1 LAST OFFPAGE TRUE
J 0
(-12940 2545);
DISPLAY 0.808511 (-12940 2545);
PAINT GREEN (-12940 2545);
DISPLAY INVISIBLE (-12940 2545);
FORCEPROP 2 LAST PATH I287
J 0
(-13100 2650);
DISPLAY 1.021277 (-13100 2650);
DISPLAY INVISIBLE (-13100 2650);
FORCEADD OFFPAGE_IN..1
R 6
(-12950 2400);
FORCEPROP 2 LAST $XR0 12H5> 
J 0
(-13133 2400);
DISPLAY 0.638298 (-13133 2400);
PAINT MONO (-13133 2400);
FORCEPROP 2 LAST $XR1 25E6<> 
J 0
(-13343 2400);
DISPLAY 0.638298 (-13343 2400);
PAINT MONO (-13343 2400);
FORCEPROP 2 LAST CDS_LIB cls
J 0
(-12950 2400);
DISPLAY INVISIBLE (-12950 2400);
FORCEPROP 1 LAST CDS_LMAN_SYM_OUTLINE -50,50,50,-50
J 0
(-12950 2400);
DISPLAY 0.468085 (-12950 2400);
PAINT GREEN (-12950 2400);
DISPLAY INVISIBLE (-12950 2400);
FORCEPROP 1 LAST BODY_TYPE COMMENT
J 0
(-12940 2265);
DISPLAY 0.808511 (-12940 2265);
PAINT GREEN (-12940 2265);
DISPLAY INVISIBLE (-12940 2265);
FORCEPROP 1 LAST OFFPAGE TRUE
J 0
(-12940 2345);
DISPLAY 0.808511 (-12940 2345);
PAINT GREEN (-12940 2345);
DISPLAY INVISIBLE (-12940 2345);
FORCEPROP 2 LAST PATH I288
J 0
(-12900 2500);
DISPLAY 1.021277 (-12900 2500);
DISPLAY INVISIBLE (-12900 2500);
FORCEADD CAPACITOR..2
(-8350 2300);
FORCEPROP 1 LAST VALUE 0.1UF
J 0
(-8300 2350);
DISPLAY 1.212766 (-8300 2350);
PAINT GREEN (-8300 2350);
FORCEPROP 0 LAST VOLTAGE 10V
J 0
(-8250 2150);
DISPLAY 1.021277 (-8250 2150);
FORCEPROP 0 LAST PACKAGE 0402
J 0
(-8250 2050);
DISPLAY 1.021277 (-8250 2050);
FORCEPROP 1 LAST PATH I289
J 0
(-8450 2350);
DISPLAY 1.212766 (-8450 2350);
PAINT GREEN (-8450 2350);
DISPLAY INVISIBLE (-8450 2350);
FORCEPROP 1 LAST CDS_LMAN_SYM_OUTLINE -50,0,50,-50
J 0
(-8350 2300);
DISPLAY 0.468085 (-8350 2300);
PAINT GREEN (-8350 2300);
DISPLAY INVISIBLE (-8350 2300);
FORCEPROP 2 LAST CDS_LIB passive
J 0
(-8350 2300);
DISPLAY INVISIBLE (-8350 2300);
FORCEPROP 1 LAST TOLERANCE 10%
J 0
(-8500 2400);
DISPLAY 1.212766 (-8500 2400);
PAINT GREEN (-8500 2400);
DISPLAY INVISIBLE (-8500 2400);
FORCEPROP 1 LAST CLS_PN G105-0B104-CK
J 0
(-8450 2350);
DISPLAY 1.212766 (-8450 2350);
PAINT GREEN (-8450 2350);
DISPLAY INVISIBLE (-8450 2350);
FORCEPROP 1 LAST $LOCATION C84
J 0
(-8250 2250);
DISPLAY 1.212766 (-8250 2250);
PAINT GREEN (-8250 2250);
FORCEPROP 0 LASTPIN (-8350 2400) $PN 1
R 1
J 0
(-8360 2410);
DISPLAY 0.680851 (-8360 2410);
PAINT MONO (-8360 2410);
FORCEPROP 0 LASTPIN (-8350 2150) $PN 2
R 1
J 2
(-8360 2140);
DISPLAY 0.680851 (-8360 2140);
PAINT MONO (-8360 2140);
FORCEPROP 0 LAST CDS_LOCATION C84
J 0
(-8300 2450);
DISPLAY 1.021277 (-8300 2450);
DISPLAY INVISIBLE (-8300 2450);
FORCEPROP 0 LAST $SEC 1
J 0
(-8300 2450);
DISPLAY 0.680851 (-8300 2450);
PAINT MONO (-8300 2450);
DISPLAY INVISIBLE (-8300 2450);
FORCEPROP 0 LAST CDS_SEC 1
J 0
(-8300 2450);
DISPLAY 1.021277 (-8300 2450);
DISPLAY INVISIBLE (-8300 2450);
FORCEADD CONN_JACK_1P_GH4_S_TH..1
(-2650 9150);
FORCEPROP 1 LAST CLS_PN G200-13091-01
J 0
(-2650 9250);
DISPLAY 1.212766 (-2650 9250);
PAINT GREEN (-2650 9250);
FORCEPROP 1 LAST VALUE 2081680-1
J 0
(-2650 9350);
DISPLAY 1.212766 (-2650 9350);
PAINT GREEN (-2650 9350);
FORCEPROP 1 LAST PATH I290
J 0
(-2600 9200);
DISPLAY 1.212766 (-2600 9200);
PAINT GREEN (-2600 9200);
DISPLAY INVISIBLE (-2600 9200);
FORCEPROP 1 LAST CDS_LMAN_SYM_OUTLINE 0,0,500,-600
J 0
(-2650 9150);
DISPLAY 0.468085 (-2650 9150);
PAINT GREEN (-2650 9150);
DISPLAY INVISIBLE (-2650 9150);
FORCEPROP 2 LAST CDS_LIB connector
J 0
(-2650 9150);
DISPLAY INVISIBLE (-2650 9150);
FORCEPROP 1 LAST LOCATION J1
J 0
(-2650 9450);
DISPLAY 1.212766 (-2650 9450);
PAINT GREEN (-2650 9450);
FORCEPROP 0 LASTPIN (-2750 9050) $PN 1
J 2
(-2760 9060);
DISPLAY 0.680851 (-2760 9060);
PAINT MONO (-2760 9060);
FORCEPROP 0 LASTPIN (-2750 8850) $PN GH1
J 2
(-2760 8860);
DISPLAY 0.680851 (-2760 8860);
PAINT MONO (-2760 8860);
FORCEPROP 0 LASTPIN (-2050 8850) $PN GH2
J 0
(-2040 8860);
DISPLAY 0.680851 (-2040 8860);
PAINT MONO (-2040 8860);
FORCEPROP 0 LASTPIN (-2750 8700) $PN GH3
J 2
(-2760 8710);
DISPLAY 0.680851 (-2760 8710);
PAINT MONO (-2760 8710);
FORCEPROP 0 LASTPIN (-2050 8700) $PN GH4
J 0
(-2040 8710);
DISPLAY 0.680851 (-2040 8710);
PAINT MONO (-2040 8710);
FORCEPROP 0 LAST $SEC 1
J 0
(-2650 9550);
DISPLAY 0.680851 (-2650 9550);
PAINT MONO (-2650 9550);
DISPLAY INVISIBLE (-2650 9550);
FORCEPROP 0 LAST CDS_SEC 1
J 0
(-2650 9550);
DISPLAY 1.021277 (-2650 9550);
DISPLAY INVISIBLE (-2650 9550);
FORCEADD GND_SG..1
(-2950 8550);
FORCEPROP 3 LASTPIN (-2900 8600) SIG_NAME SG\g
J 0
(-2890 8610);
DISPLAY 0.659574 (-2890 8610);
PAINT MONO (-2890 8610);
DISPLAY INVISIBLE (-2890 8610);
FORCEPROP 1 LAST HDL_POWER SG
J 1
(-2900 8450);
DISPLAY 0.808511 (-2900 8450);
PAINT GREEN (-2900 8450);
FORCEPROP 1 LAST PATH I291
J 0
(-2915 8550);
DISPLAY 0.808511 (-2915 8550);
PAINT GREEN (-2915 8550);
DISPLAY INVISIBLE (-2915 8550);
FORCEPROP 1 LAST BODY_TYPE PLUMBING
J 0
(-2935 8535);
DISPLAY 0.808511 (-2935 8535);
PAINT GREEN (-2935 8535);
DISPLAY INVISIBLE (-2935 8535);
FORCEPROP 2 LAST CDS_LIB cls
J 0
(-2950 8550);
DISPLAY INVISIBLE (-2950 8550);
FORCEPROP 1 LAST CDS_LMAN_SYM_OUTLINE 0,0,100,-50
J 0
(-2950 8550);
DISPLAY 0.468085 (-2950 8550);
PAINT GREEN (-2950 8550);
DISPLAY INVISIBLE (-2950 8550);
FORCEADD GND_SG..1
(-2900 6400);
FORCEPROP 3 LASTPIN (-2850 6450) SIG_NAME SG\g
J 0
(-2840 6460);
DISPLAY 0.659574 (-2840 6460);
PAINT MONO (-2840 6460);
DISPLAY INVISIBLE (-2840 6460);
FORCEPROP 1 LAST HDL_POWER SG
J 1
(-2850 6300);
DISPLAY 0.808511 (-2850 6300);
PAINT GREEN (-2850 6300);
FORCEPROP 1 LAST PATH I292
J 0
(-2865 6400);
DISPLAY 0.808511 (-2865 6400);
PAINT GREEN (-2865 6400);
DISPLAY INVISIBLE (-2865 6400);
FORCEPROP 1 LAST BODY_TYPE PLUMBING
J 0
(-2885 6385);
DISPLAY 0.808511 (-2885 6385);
PAINT GREEN (-2885 6385);
DISPLAY INVISIBLE (-2885 6385);
FORCEPROP 2 LAST CDS_LIB cls
J 0
(-2900 6400);
DISPLAY INVISIBLE (-2900 6400);
FORCEPROP 1 LAST CDS_LMAN_SYM_OUTLINE 0,0,100,-50
J 0
(-2900 6400);
DISPLAY 0.468085 (-2900 6400);
PAINT GREEN (-2900 6400);
DISPLAY INVISIBLE (-2900 6400);
FORCEADD GND_SG..1
(-1900 6400);
FORCEPROP 3 LASTPIN (-1850 6450) SIG_NAME SG\g
J 0
(-1840 6460);
DISPLAY 0.659574 (-1840 6460);
PAINT MONO (-1840 6460);
DISPLAY INVISIBLE (-1840 6460);
FORCEPROP 1 LAST HDL_POWER SG
J 1
(-1850 6300);
DISPLAY 0.808511 (-1850 6300);
PAINT GREEN (-1850 6300);
FORCEPROP 1 LAST PATH I293
J 0
(-1865 6400);
DISPLAY 0.808511 (-1865 6400);
PAINT GREEN (-1865 6400);
DISPLAY INVISIBLE (-1865 6400);
FORCEPROP 1 LAST BODY_TYPE PLUMBING
J 0
(-1885 6385);
DISPLAY 0.808511 (-1885 6385);
PAINT GREEN (-1885 6385);
DISPLAY INVISIBLE (-1885 6385);
FORCEPROP 1 LAST CDS_LMAN_SYM_OUTLINE 0,0,100,-50
J 0
(-1900 6400);
DISPLAY 0.468085 (-1900 6400);
PAINT GREEN (-1900 6400);
DISPLAY INVISIBLE (-1900 6400);
FORCEPROP 2 LAST CDS_LIB cls
J 0
(-1900 6400);
DISPLAY INVISIBLE (-1900 6400);
FORCEADD CONN_JACK_1P_GH4_S_TH..1
(-2600 7000);
FORCEPROP 1 LAST CLS_PN G200-13091-01
J 0
(-2600 7100);
DISPLAY 1.212766 (-2600 7100);
PAINT GREEN (-2600 7100);
FORCEPROP 1 LAST VALUE 2081680-1
J 0
(-2600 7200);
DISPLAY 1.212766 (-2600 7200);
PAINT GREEN (-2600 7200);
FORCEPROP 1 LAST PATH I294
J 0
(-2550 7050);
DISPLAY 1.212766 (-2550 7050);
PAINT GREEN (-2550 7050);
DISPLAY INVISIBLE (-2550 7050);
FORCEPROP 1 LAST CDS_LMAN_SYM_OUTLINE 0,0,500,-600
J 0
(-2600 7000);
DISPLAY 0.468085 (-2600 7000);
PAINT GREEN (-2600 7000);
DISPLAY INVISIBLE (-2600 7000);
FORCEPROP 2 LAST CDS_LIB connector
J 0
(-2600 7000);
DISPLAY INVISIBLE (-2600 7000);
FORCEPROP 1 LAST LOCATION J2
J 0
(-2600 7300);
DISPLAY 1.212766 (-2600 7300);
PAINT GREEN (-2600 7300);
FORCEPROP 0 LASTPIN (-2700 6900) $PN 1
J 2
(-2710 6910);
DISPLAY 0.680851 (-2710 6910);
PAINT MONO (-2710 6910);
FORCEPROP 0 LASTPIN (-2700 6700) $PN GH1
J 2
(-2710 6710);
DISPLAY 0.680851 (-2710 6710);
PAINT MONO (-2710 6710);
FORCEPROP 0 LASTPIN (-2000 6700) $PN GH2
J 0
(-1990 6710);
DISPLAY 0.680851 (-1990 6710);
PAINT MONO (-1990 6710);
FORCEPROP 0 LASTPIN (-2700 6550) $PN GH3
J 2
(-2710 6560);
DISPLAY 0.680851 (-2710 6560);
PAINT MONO (-2710 6560);
FORCEPROP 0 LASTPIN (-2000 6550) $PN GH4
J 0
(-1990 6560);
DISPLAY 0.680851 (-1990 6560);
PAINT MONO (-1990 6560);
FORCEPROP 0 LAST $SEC 1
J 0
(-2600 7400);
DISPLAY 0.680851 (-2600 7400);
PAINT MONO (-2600 7400);
DISPLAY INVISIBLE (-2600 7400);
FORCEPROP 0 LAST CDS_SEC 1
J 0
(-2600 7400);
DISPLAY 1.021277 (-2600 7400);
DISPLAY INVISIBLE (-2600 7400);
FORCEADD GND_SG..1
(-2900 4250);
FORCEPROP 3 LASTPIN (-2850 4300) SIG_NAME SG\g
J 0
(-2840 4310);
DISPLAY 0.659574 (-2840 4310);
PAINT MONO (-2840 4310);
DISPLAY INVISIBLE (-2840 4310);
FORCEPROP 1 LAST HDL_POWER SG
J 1
(-2850 4150);
DISPLAY 0.808511 (-2850 4150);
PAINT GREEN (-2850 4150);
FORCEPROP 1 LAST PATH I295
J 0
(-2865 4250);
DISPLAY 0.808511 (-2865 4250);
PAINT GREEN (-2865 4250);
DISPLAY INVISIBLE (-2865 4250);
FORCEPROP 1 LAST BODY_TYPE PLUMBING
J 0
(-2885 4235);
DISPLAY 0.808511 (-2885 4235);
PAINT GREEN (-2885 4235);
DISPLAY INVISIBLE (-2885 4235);
FORCEPROP 2 LAST CDS_LIB cls
J 0
(-2900 4250);
DISPLAY INVISIBLE (-2900 4250);
FORCEPROP 1 LAST CDS_LMAN_SYM_OUTLINE 0,0,100,-50
J 0
(-2900 4250);
DISPLAY 0.468085 (-2900 4250);
PAINT GREEN (-2900 4250);
DISPLAY INVISIBLE (-2900 4250);
FORCEADD GND_SG..1
(-1900 4250);
FORCEPROP 3 LASTPIN (-1850 4300) SIG_NAME SG\g
J 0
(-1840 4310);
DISPLAY 0.659574 (-1840 4310);
PAINT MONO (-1840 4310);
DISPLAY INVISIBLE (-1840 4310);
FORCEPROP 1 LAST HDL_POWER SG
J 1
(-1850 4150);
DISPLAY 0.808511 (-1850 4150);
PAINT GREEN (-1850 4150);
FORCEPROP 1 LAST PATH I296
J 0
(-1865 4250);
DISPLAY 0.808511 (-1865 4250);
PAINT GREEN (-1865 4250);
DISPLAY INVISIBLE (-1865 4250);
FORCEPROP 1 LAST BODY_TYPE PLUMBING
J 0
(-1885 4235);
DISPLAY 0.808511 (-1885 4235);
PAINT GREEN (-1885 4235);
DISPLAY INVISIBLE (-1885 4235);
FORCEPROP 1 LAST CDS_LMAN_SYM_OUTLINE 0,0,100,-50
J 0
(-1900 4250);
DISPLAY 0.468085 (-1900 4250);
PAINT GREEN (-1900 4250);
DISPLAY INVISIBLE (-1900 4250);
FORCEPROP 2 LAST CDS_LIB cls
J 0
(-1900 4250);
DISPLAY INVISIBLE (-1900 4250);
FORCEADD CONN_JACK_1P_GH4_S_TH..1
(-2600 4850);
FORCEPROP 1 LAST CLS_PN G200-13091-01
J 0
(-2600 4950);
DISPLAY 1.212766 (-2600 4950);
PAINT GREEN (-2600 4950);
FORCEPROP 1 LAST VALUE 2081680-1
J 0
(-2600 5050);
DISPLAY 1.212766 (-2600 5050);
PAINT GREEN (-2600 5050);
FORCEPROP 1 LAST PATH I297
J 0
(-2550 4900);
DISPLAY 1.212766 (-2550 4900);
PAINT GREEN (-2550 4900);
DISPLAY INVISIBLE (-2550 4900);
FORCEPROP 1 LAST CDS_LMAN_SYM_OUTLINE 0,0,500,-600
J 0
(-2600 4850);
DISPLAY 0.468085 (-2600 4850);
PAINT GREEN (-2600 4850);
DISPLAY INVISIBLE (-2600 4850);
FORCEPROP 2 LAST CDS_LIB connector
J 0
(-2600 4850);
DISPLAY INVISIBLE (-2600 4850);
FORCEPROP 1 LAST LOCATION J3
J 0
(-2600 5150);
DISPLAY 1.212766 (-2600 5150);
PAINT GREEN (-2600 5150);
FORCEPROP 0 LASTPIN (-2700 4750) $PN 1
J 2
(-2710 4760);
DISPLAY 0.680851 (-2710 4760);
PAINT MONO (-2710 4760);
FORCEPROP 0 LASTPIN (-2700 4550) $PN GH1
J 2
(-2710 4560);
DISPLAY 0.680851 (-2710 4560);
PAINT MONO (-2710 4560);
FORCEPROP 0 LASTPIN (-2000 4550) $PN GH2
J 0
(-1990 4560);
DISPLAY 0.680851 (-1990 4560);
PAINT MONO (-1990 4560);
FORCEPROP 0 LASTPIN (-2700 4400) $PN GH3
J 2
(-2710 4410);
DISPLAY 0.680851 (-2710 4410);
PAINT MONO (-2710 4410);
FORCEPROP 0 LASTPIN (-2000 4400) $PN GH4
J 0
(-1990 4410);
DISPLAY 0.680851 (-1990 4410);
PAINT MONO (-1990 4410);
FORCEPROP 0 LAST $SEC 1
J 0
(-2600 5250);
DISPLAY 0.680851 (-2600 5250);
PAINT MONO (-2600 5250);
DISPLAY INVISIBLE (-2600 5250);
FORCEPROP 0 LAST CDS_SEC 1
J 0
(-2600 5250);
DISPLAY 1.021277 (-2600 5250);
DISPLAY INVISIBLE (-2600 5250);
FORCEADD GND_SG..1
(-2850 2100);
FORCEPROP 3 LASTPIN (-2800 2150) SIG_NAME SG\g
J 0
(-2790 2160);
DISPLAY 0.659574 (-2790 2160);
PAINT MONO (-2790 2160);
DISPLAY INVISIBLE (-2790 2160);
FORCEPROP 1 LAST HDL_POWER SG
J 1
(-2800 2000);
DISPLAY 0.808511 (-2800 2000);
PAINT GREEN (-2800 2000);
FORCEPROP 1 LAST PATH I298
J 0
(-2815 2100);
DISPLAY 0.808511 (-2815 2100);
PAINT GREEN (-2815 2100);
DISPLAY INVISIBLE (-2815 2100);
FORCEPROP 1 LAST BODY_TYPE PLUMBING
J 0
(-2835 2085);
DISPLAY 0.808511 (-2835 2085);
PAINT GREEN (-2835 2085);
DISPLAY INVISIBLE (-2835 2085);
FORCEPROP 2 LAST CDS_LIB cls
J 0
(-2850 2100);
DISPLAY INVISIBLE (-2850 2100);
FORCEPROP 1 LAST CDS_LMAN_SYM_OUTLINE 0,0,100,-50
J 0
(-2850 2100);
DISPLAY 0.468085 (-2850 2100);
PAINT GREEN (-2850 2100);
DISPLAY INVISIBLE (-2850 2100);
FORCEADD GND_SG..1
(-1850 2100);
FORCEPROP 3 LASTPIN (-1800 2150) SIG_NAME SG\g
J 0
(-1790 2160);
DISPLAY 0.659574 (-1790 2160);
PAINT MONO (-1790 2160);
DISPLAY INVISIBLE (-1790 2160);
FORCEPROP 1 LAST HDL_POWER SG
J 1
(-1800 2000);
DISPLAY 0.808511 (-1800 2000);
PAINT GREEN (-1800 2000);
FORCEPROP 1 LAST PATH I299
J 0
(-1815 2100);
DISPLAY 0.808511 (-1815 2100);
PAINT GREEN (-1815 2100);
DISPLAY INVISIBLE (-1815 2100);
FORCEPROP 1 LAST BODY_TYPE PLUMBING
J 0
(-1835 2085);
DISPLAY 0.808511 (-1835 2085);
PAINT GREEN (-1835 2085);
DISPLAY INVISIBLE (-1835 2085);
FORCEPROP 1 LAST CDS_LMAN_SYM_OUTLINE 0,0,100,-50
J 0
(-1850 2100);
DISPLAY 0.468085 (-1850 2100);
PAINT GREEN (-1850 2100);
DISPLAY INVISIBLE (-1850 2100);
FORCEPROP 2 LAST CDS_LIB cls
J 0
(-1850 2100);
DISPLAY INVISIBLE (-1850 2100);
FORCEADD CONN_JACK_1P_GH4_S_TH..1
(-2550 2700);
FORCEPROP 1 LAST VALUE 2081680-1
J 0
(-2550 2900);
DISPLAY 1.212766 (-2550 2900);
PAINT GREEN (-2550 2900);
FORCEPROP 1 LAST CLS_PN G200-13091-01
J 0
(-2550 2800);
DISPLAY 1.212766 (-2550 2800);
PAINT GREEN (-2550 2800);
FORCEPROP 1 LAST PATH I300
J 0
(-2500 2750);
DISPLAY 1.212766 (-2500 2750);
PAINT GREEN (-2500 2750);
DISPLAY INVISIBLE (-2500 2750);
FORCEPROP 1 LAST CDS_LMAN_SYM_OUTLINE 0,0,500,-600
J 0
(-2550 2700);
DISPLAY 0.468085 (-2550 2700);
PAINT GREEN (-2550 2700);
DISPLAY INVISIBLE (-2550 2700);
FORCEPROP 2 LAST CDS_LIB connector
J 0
(-2550 2700);
DISPLAY INVISIBLE (-2550 2700);
FORCEPROP 1 LAST LOCATION J4
J 0
(-2550 3000);
DISPLAY 1.212766 (-2550 3000);
PAINT GREEN (-2550 3000);
FORCEPROP 0 LASTPIN (-2650 2600) $PN 1
J 2
(-2660 2610);
DISPLAY 0.680851 (-2660 2610);
PAINT MONO (-2660 2610);
FORCEPROP 0 LASTPIN (-2650 2400) $PN GH1
J 2
(-2660 2410);
DISPLAY 0.680851 (-2660 2410);
PAINT MONO (-2660 2410);
FORCEPROP 0 LASTPIN (-1950 2400) $PN GH2
J 0
(-1940 2410);
DISPLAY 0.680851 (-1940 2410);
PAINT MONO (-1940 2410);
FORCEPROP 0 LASTPIN (-2650 2250) $PN GH3
J 2
(-2660 2260);
DISPLAY 0.680851 (-2660 2260);
PAINT MONO (-2660 2260);
FORCEPROP 0 LASTPIN (-1950 2250) $PN GH4
J 0
(-1940 2260);
DISPLAY 0.680851 (-1940 2260);
PAINT MONO (-1940 2260);
FORCEPROP 0 LAST $SEC 1
J 0
(-2550 3100);
DISPLAY 0.680851 (-2550 3100);
PAINT MONO (-2550 3100);
DISPLAY INVISIBLE (-2550 3100);
FORCEPROP 0 LAST CDS_SEC 1
J 0
(-2550 3100);
DISPLAY 1.021277 (-2550 3100);
DISPLAY INVISIBLE (-2550 3100);
FORCEADD GND_SG..1
(-10050 8000);
FORCEPROP 3 LASTPIN (-10000 8050) SIG_NAME SG\g
J 0
(-9990 8060);
DISPLAY 0.659574 (-9990 8060);
PAINT MONO (-9990 8060);
DISPLAY INVISIBLE (-9990 8060);
FORCEPROP 1 LAST HDL_POWER SG
J 1
(-10000 7900);
DISPLAY 0.808511 (-10000 7900);
PAINT GREEN (-10000 7900);
FORCEPROP 1 LAST BODY_TYPE PLUMBING
J 0
(-10035 7985);
DISPLAY 0.808511 (-10035 7985);
PAINT GREEN (-10035 7985);
DISPLAY INVISIBLE (-10035 7985);
FORCEPROP 1 LAST CDS_LMAN_SYM_OUTLINE 0,0,100,-50
J 0
(-10050 8000);
DISPLAY 0.468085 (-10050 8000);
PAINT GREEN (-10050 8000);
DISPLAY INVISIBLE (-10050 8000);
FORCEPROP 2 LAST CDS_LIB cls
J 0
(-10050 8000);
DISPLAY INVISIBLE (-10050 8000);
FORCEPROP 1 LAST PATH I317
J 0
(-10015 8000);
DISPLAY 0.808511 (-10015 8000);
PAINT GREEN (-10015 8000);
DISPLAY INVISIBLE (-10015 8000);
FORCEADD CAPACITOR..1
R 1
(-10000 8250);
FORCEPROP 1 LAST VALUE 18PF
J 0
(-10350 8250);
DISPLAY 0.978723 (-10350 8250);
PAINT GREEN (-10350 8250);
FORCEPROP 0 LAST PACKAGE 0201
J 0
(-10350 8350);
DISPLAY 0.808511 (-10350 8350);
FORCEPROP 2 LASTPIN (-10000 8400) SIG_NAME UN$12$CAPACITOR$I318$2
J 0
(-9990 8410);
DISPLAY 0.659574 (-9990 8410);
PAINT MONO (-9990 8410);
DISPLAY INVISIBLE (-9990 8410);
FORCEPROP 2 LAST CDS_LIB passive
J 0
(-10000 8250);
DISPLAY INVISIBLE (-10000 8250);
FORCEPROP 1 LAST CDS_LMAN_SYM_OUTLINE 0,50,50,-50
R 1
J 0
(-10000 8250);
DISPLAY 0.468085 (-10000 8250);
PAINT GREEN (-10000 8250);
DISPLAY INVISIBLE (-10000 8250);
FORCEPROP 1 LAST CLS_PN G104-0A180-FJ
R 1
J 2
(-10100 8200);
DISPLAY 1.212766 (-10100 8200);
PAINT GREEN (-10100 8200);
DISPLAY INVISIBLE (-10100 8200);
FORCEPROP 1 LAST TOLERANCE 5%
R 1
J 2
(-10100 8150);
DISPLAY 1.212766 (-10100 8150);
PAINT GREEN (-10100 8150);
DISPLAY INVISIBLE (-10100 8150);
FORCEPROP 1 LAST PATH I318
R 1
J 2
(-10100 8200);
DISPLAY 1.212766 (-10100 8200);
PAINT GREEN (-10100 8200);
DISPLAY INVISIBLE (-10100 8200);
FORCEPROP 1 LAST $LOCATION C310
J 2
(-10200 8150);
DISPLAY 0.978723 (-10200 8150);
PAINT GREEN (-10200 8150);
FORCEPROP 0 LASTPIN (-10000 8150) $PN 1
R 1
J 2
(-10010 8140);
DISPLAY 0.680851 (-10010 8140);
PAINT MONO (-10010 8140);
FORCEPROP 0 LASTPIN (-10000 8400) $PN 2
R 1
J 0
(-10010 8410);
DISPLAY 0.680851 (-10010 8410);
PAINT MONO (-10010 8410);
FORCEPROP 0 LAST CDS_LOCATION C310
R 1
J 0
(-10350 8400);
DISPLAY 1.021277 (-10350 8400);
DISPLAY INVISIBLE (-10350 8400);
FORCEPROP 0 LAST $SEC 1
R 1
J 0
(-10350 8400);
DISPLAY 0.680851 (-10350 8400);
PAINT MONO (-10350 8400);
DISPLAY INVISIBLE (-10350 8400);
FORCEPROP 0 LAST CDS_SEC 1
R 1
J 0
(-10350 8400);
DISPLAY 1.021277 (-10350 8400);
DISPLAY INVISIBLE (-10350 8400);
FORCEADD RESISTOR..2
R 6
(-10000 8600);
FORCEPROP 1 LAST VALUE 0OHM
J 0
(-10350 8700);
DISPLAY 0.978723 (-10350 8700);
PAINT GREEN (-10350 8700);
FORCEPROP 0 LAST PACKAGE 0402
J 2
(-10200 8600);
DISPLAY 0.808511 (-10200 8600);
FORCEPROP 1 LAST CLS_PN G155-100R0-J0
J 0
(-10136 8343);
DISPLAY 1.212766 (-10136 8343);
PAINT GREEN (-10136 8343);
DISPLAY INVISIBLE (-10136 8343);
FORCEPROP 1 LAST TOLERANCE -
J 0
(-10197 8288);
DISPLAY 1.212766 (-10197 8288);
PAINT GREEN (-10197 8288);
DISPLAY INVISIBLE (-10197 8288);
FORCEPROP 2 LAST CDS_LIB passive
R 3
J 2
(-10000 8553);
DISPLAY INVISIBLE (-10000 8553);
FORCEPROP 1 LAST CDS_LMAN_SYM_OUTLINE -50,50,50,-100
J 0
(-10000 8578);
DISPLAY 0.468085 (-10000 8578);
PAINT GREEN (-10000 8578);
DISPLAY INVISIBLE (-10000 8578);
FORCEPROP 1 LAST PATH I319
J 0
(-10197 8495);
DISPLAY 1.212766 (-10197 8495);
PAINT GREEN (-10197 8495);
DISPLAY INVISIBLE (-10197 8495);
FORCEPROP 1 LAST $LOCATION R492
J 0
(-10350 8500);
DISPLAY 0.978723 (-10350 8500);
PAINT GREEN (-10350 8500);
FORCEPROP 0 LASTPIN (-10000 8500) $PN 1
R 1
J 2
(-10010 8490);
DISPLAY 0.680851 (-10010 8490);
PAINT MONO (-10010 8490);
FORCEPROP 0 LASTPIN (-10000 8750) $PN 2
R 1
J 0
(-10010 8760);
DISPLAY 0.680851 (-10010 8760);
PAINT MONO (-10010 8760);
FORCEPROP 0 LAST CDS_LOCATION R492
J 0
(-10350 8750);
DISPLAY 1.021277 (-10350 8750);
DISPLAY INVISIBLE (-10350 8750);
FORCEPROP 0 LAST $SEC 1
J 0
(-10350 8750);
DISPLAY 0.680851 (-10350 8750);
PAINT MONO (-10350 8750);
DISPLAY INVISIBLE (-10350 8750);
FORCEPROP 0 LAST CDS_SEC 1
J 0
(-10350 8750);
DISPLAY 1.021277 (-10350 8750);
DISPLAY INVISIBLE (-10350 8750);
FORCEADD RESISTOR..2
R 4
(-9750 8350);
FORCEPROP 1 LAST VALUE 1MOHM
J 0
(-9700 8450);
DISPLAY 0.978723 (-9700 8450);
PAINT GREEN (-9700 8450);
FORCEPROP 0 LAST PACKAGE 0402
J 0
(-9700 8350);
DISPLAY 0.808511 (-9700 8350);
FORCEPROP 2 LAST CDS_LIB passive
R 1
J 0
(-9750 8350);
DISPLAY INVISIBLE (-9750 8350);
FORCEPROP 1 LAST CDS_LMAN_SYM_OUTLINE -50,50,50,-100
R 2
J 0
(-9750 8350);
DISPLAY 0.468085 (-9750 8350);
PAINT GREEN (-9750 8350);
DISPLAY INVISIBLE (-9750 8350);
FORCEPROP 1 LAST TOLERANCE 1%
R 2
J 0
(-9553 8095);
DISPLAY 1.212766 (-9553 8095);
PAINT GREEN (-9553 8095);
DISPLAY INVISIBLE (-9553 8095);
FORCEPROP 1 LAST CLS_PN G155-11004-01
R 2
J 0
(-9614 8150);
DISPLAY 1.212766 (-9614 8150);
PAINT GREEN (-9614 8150);
DISPLAY INVISIBLE (-9614 8150);
FORCEPROP 1 LAST PATH I320
R 2
J 0
(-9553 8245);
DISPLAY 1.212766 (-9553 8245);
PAINT GREEN (-9553 8245);
DISPLAY INVISIBLE (-9553 8245);
FORCEPROP 1 LAST $LOCATION R496
J 0
(-9700 8250);
DISPLAY 0.978723 (-9700 8250);
PAINT GREEN (-9700 8250);
FORCEPROP 0 LASTPIN (-9750 8250) $PN 1
R 1
J 2
(-9760 8240);
DISPLAY 0.680851 (-9760 8240);
PAINT MONO (-9760 8240);
FORCEPROP 0 LASTPIN (-9750 8500) $PN 2
R 1
J 0
(-9760 8510);
DISPLAY 0.680851 (-9760 8510);
PAINT MONO (-9760 8510);
FORCEPROP 0 LAST CDS_LOCATION R496
J 0
(-9700 8500);
DISPLAY 1.021277 (-9700 8500);
DISPLAY INVISIBLE (-9700 8500);
FORCEPROP 0 LAST $SEC 1
J 0
(-9700 8500);
DISPLAY 0.680851 (-9700 8500);
PAINT MONO (-9700 8500);
DISPLAY INVISIBLE (-9700 8500);
FORCEPROP 0 LAST CDS_SEC 1
J 0
(-9700 8500);
DISPLAY 1.021277 (-9700 8500);
DISPLAY INVISIBLE (-9700 8500);
FORCEADD CAPACITOR..1
R 1
(-9950 6100);
FORCEPROP 1 LAST VALUE 18PF
J 0
(-10300 6100);
DISPLAY 0.978723 (-10300 6100);
PAINT GREEN (-10300 6100);
FORCEPROP 0 LAST PACKAGE 0201
J 0
(-10300 6200);
DISPLAY 0.808511 (-10300 6200);
FORCEPROP 2 LASTPIN (-9950 6250) SIG_NAME UN$12$CAPACITOR$I321$2
J 0
(-9940 6260);
DISPLAY 0.659574 (-9940 6260);
PAINT MONO (-9940 6260);
DISPLAY INVISIBLE (-9940 6260);
FORCEPROP 1 LAST PATH I321
R 1
J 2
(-10050 6050);
DISPLAY 1.212766 (-10050 6050);
PAINT GREEN (-10050 6050);
DISPLAY INVISIBLE (-10050 6050);
FORCEPROP 1 LAST TOLERANCE 5%
R 1
J 2
(-10050 6000);
DISPLAY 1.212766 (-10050 6000);
PAINT GREEN (-10050 6000);
DISPLAY INVISIBLE (-10050 6000);
FORCEPROP 1 LAST CLS_PN G104-0A180-FJ
R 1
J 2
(-10050 6050);
DISPLAY 1.212766 (-10050 6050);
PAINT GREEN (-10050 6050);
DISPLAY INVISIBLE (-10050 6050);
FORCEPROP 1 LAST CDS_LMAN_SYM_OUTLINE 0,50,50,-50
R 1
J 0
(-9950 6100);
DISPLAY 0.468085 (-9950 6100);
PAINT GREEN (-9950 6100);
DISPLAY INVISIBLE (-9950 6100);
FORCEPROP 2 LAST CDS_LIB passive
J 0
(-9950 6100);
DISPLAY INVISIBLE (-9950 6100);
FORCEPROP 1 LAST $LOCATION C311
J 2
(-10150 6000);
DISPLAY 0.978723 (-10150 6000);
PAINT GREEN (-10150 6000);
FORCEPROP 0 LASTPIN (-9950 6000) $PN 1
R 1
J 2
(-9960 5990);
DISPLAY 0.680851 (-9960 5990);
PAINT MONO (-9960 5990);
FORCEPROP 0 LASTPIN (-9950 6250) $PN 2
R 1
J 0
(-9960 6260);
DISPLAY 0.680851 (-9960 6260);
PAINT MONO (-9960 6260);
FORCEPROP 0 LAST CDS_LOCATION C311
R 1
J 0
(-10300 6250);
DISPLAY 1.021277 (-10300 6250);
DISPLAY INVISIBLE (-10300 6250);
FORCEPROP 0 LAST $SEC 1
R 1
J 0
(-10300 6250);
DISPLAY 0.680851 (-10300 6250);
PAINT MONO (-10300 6250);
DISPLAY INVISIBLE (-10300 6250);
FORCEPROP 0 LAST CDS_SEC 1
R 1
J 0
(-10300 6250);
DISPLAY 1.021277 (-10300 6250);
DISPLAY INVISIBLE (-10300 6250);
FORCEADD RESISTOR..2
R 4
(-9700 6200);
FORCEPROP 1 LAST VALUE 1MOHM
J 0
(-9650 6300);
DISPLAY 0.978723 (-9650 6300);
PAINT GREEN (-9650 6300);
FORCEPROP 0 LAST PACKAGE 0402
J 0
(-9650 6200);
DISPLAY 0.808511 (-9650 6200);
FORCEPROP 1 LAST PATH I322
R 2
J 0
(-9503 6095);
DISPLAY 1.212766 (-9503 6095);
PAINT GREEN (-9503 6095);
DISPLAY INVISIBLE (-9503 6095);
FORCEPROP 1 LAST CLS_PN G155-11004-01
R 2
J 0
(-9564 6000);
DISPLAY 1.212766 (-9564 6000);
PAINT GREEN (-9564 6000);
DISPLAY INVISIBLE (-9564 6000);
FORCEPROP 1 LAST TOLERANCE 1%
R 2
J 0
(-9503 5945);
DISPLAY 1.212766 (-9503 5945);
PAINT GREEN (-9503 5945);
DISPLAY INVISIBLE (-9503 5945);
FORCEPROP 1 LAST CDS_LMAN_SYM_OUTLINE -50,50,50,-100
R 2
J 0
(-9700 6200);
DISPLAY 0.468085 (-9700 6200);
PAINT GREEN (-9700 6200);
DISPLAY INVISIBLE (-9700 6200);
FORCEPROP 2 LAST CDS_LIB passive
R 1
J 0
(-9700 6200);
DISPLAY INVISIBLE (-9700 6200);
FORCEPROP 1 LAST $LOCATION R497
J 0
(-9650 6100);
DISPLAY 0.978723 (-9650 6100);
PAINT GREEN (-9650 6100);
FORCEPROP 0 LASTPIN (-9700 6100) $PN 1
R 1
J 2
(-9710 6090);
DISPLAY 0.680851 (-9710 6090);
PAINT MONO (-9710 6090);
FORCEPROP 0 LASTPIN (-9700 6350) $PN 2
R 1
J 0
(-9710 6360);
DISPLAY 0.680851 (-9710 6360);
PAINT MONO (-9710 6360);
FORCEPROP 0 LAST CDS_LOCATION R497
J 0
(-9650 6350);
DISPLAY 1.021277 (-9650 6350);
DISPLAY INVISIBLE (-9650 6350);
FORCEPROP 0 LAST $SEC 1
J 0
(-9650 6350);
DISPLAY 0.680851 (-9650 6350);
PAINT MONO (-9650 6350);
DISPLAY INVISIBLE (-9650 6350);
FORCEPROP 0 LAST CDS_SEC 1
J 0
(-9650 6350);
DISPLAY 1.021277 (-9650 6350);
DISPLAY INVISIBLE (-9650 6350);
FORCEADD RESISTOR..2
R 6
(-9950 6450);
FORCEPROP 1 LAST VALUE 0OHM
J 0
(-10300 6550);
DISPLAY 0.978723 (-10300 6550);
PAINT GREEN (-10300 6550);
FORCEPROP 0 LAST PACKAGE 0402
J 2
(-10150 6450);
DISPLAY 0.808511 (-10150 6450);
FORCEPROP 1 LAST CLS_PN G155-100R0-J0
J 0
(-10086 6193);
DISPLAY 1.212766 (-10086 6193);
PAINT GREEN (-10086 6193);
DISPLAY INVISIBLE (-10086 6193);
FORCEPROP 1 LAST TOLERANCE -
J 0
(-10147 6138);
DISPLAY 1.212766 (-10147 6138);
PAINT GREEN (-10147 6138);
DISPLAY INVISIBLE (-10147 6138);
FORCEPROP 1 LAST PATH I323
J 0
(-10147 6345);
DISPLAY 1.212766 (-10147 6345);
PAINT GREEN (-10147 6345);
DISPLAY INVISIBLE (-10147 6345);
FORCEPROP 1 LAST CDS_LMAN_SYM_OUTLINE -50,50,50,-100
J 0
(-9950 6428);
DISPLAY 0.468085 (-9950 6428);
PAINT GREEN (-9950 6428);
DISPLAY INVISIBLE (-9950 6428);
FORCEPROP 2 LAST CDS_LIB passive
R 3
J 2
(-9950 6403);
DISPLAY INVISIBLE (-9950 6403);
FORCEPROP 1 LAST $LOCATION R493
J 0
(-10300 6350);
DISPLAY 0.978723 (-10300 6350);
PAINT GREEN (-10300 6350);
FORCEPROP 0 LASTPIN (-9950 6350) $PN 1
R 1
J 2
(-9960 6340);
DISPLAY 0.680851 (-9960 6340);
PAINT MONO (-9960 6340);
FORCEPROP 0 LASTPIN (-9950 6600) $PN 2
R 1
J 0
(-9960 6610);
DISPLAY 0.680851 (-9960 6610);
PAINT MONO (-9960 6610);
FORCEPROP 0 LAST CDS_LOCATION R493
J 0
(-10300 6600);
DISPLAY 1.021277 (-10300 6600);
DISPLAY INVISIBLE (-10300 6600);
FORCEPROP 0 LAST $SEC 1
J 0
(-10300 6600);
DISPLAY 0.680851 (-10300 6600);
PAINT MONO (-10300 6600);
DISPLAY INVISIBLE (-10300 6600);
FORCEPROP 0 LAST CDS_SEC 1
J 0
(-10300 6600);
DISPLAY 1.021277 (-10300 6600);
DISPLAY INVISIBLE (-10300 6600);
FORCEADD GND_SG..1
(-10000 5850);
FORCEPROP 3 LASTPIN (-9950 5900) SIG_NAME SG\g
J 0
(-9940 5910);
DISPLAY 0.659574 (-9940 5910);
PAINT MONO (-9940 5910);
DISPLAY INVISIBLE (-9940 5910);
FORCEPROP 1 LAST HDL_POWER SG
J 1
(-9950 5750);
DISPLAY 0.808511 (-9950 5750);
PAINT GREEN (-9950 5750);
FORCEPROP 1 LAST PATH I324
J 0
(-9965 5850);
DISPLAY 0.808511 (-9965 5850);
PAINT GREEN (-9965 5850);
DISPLAY INVISIBLE (-9965 5850);
FORCEPROP 2 LAST CDS_LIB cls
J 0
(-10000 5850);
DISPLAY INVISIBLE (-10000 5850);
FORCEPROP 1 LAST CDS_LMAN_SYM_OUTLINE 0,0,100,-50
J 0
(-10000 5850);
DISPLAY 0.468085 (-10000 5850);
PAINT GREEN (-10000 5850);
DISPLAY INVISIBLE (-10000 5850);
FORCEPROP 1 LAST BODY_TYPE PLUMBING
J 0
(-9985 5835);
DISPLAY 0.808511 (-9985 5835);
PAINT GREEN (-9985 5835);
DISPLAY INVISIBLE (-9985 5835);
FORCEADD GND_SG..1
(-10000 3700);
FORCEPROP 3 LASTPIN (-9950 3750) SIG_NAME SG\g
J 0
(-9940 3760);
DISPLAY 0.659574 (-9940 3760);
PAINT MONO (-9940 3760);
DISPLAY INVISIBLE (-9940 3760);
FORCEPROP 1 LAST HDL_POWER SG
J 1
(-9950 3600);
DISPLAY 0.808511 (-9950 3600);
PAINT GREEN (-9950 3600);
FORCEPROP 1 LAST PATH I325
J 0
(-9965 3700);
DISPLAY 0.808511 (-9965 3700);
PAINT GREEN (-9965 3700);
DISPLAY INVISIBLE (-9965 3700);
FORCEPROP 1 LAST BODY_TYPE PLUMBING
J 0
(-9985 3685);
DISPLAY 0.808511 (-9985 3685);
PAINT GREEN (-9985 3685);
DISPLAY INVISIBLE (-9985 3685);
FORCEPROP 1 LAST CDS_LMAN_SYM_OUTLINE 0,0,100,-50
J 0
(-10000 3700);
DISPLAY 0.468085 (-10000 3700);
PAINT GREEN (-10000 3700);
DISPLAY INVISIBLE (-10000 3700);
FORCEPROP 2 LAST CDS_LIB cls
J 0
(-10000 3700);
DISPLAY INVISIBLE (-10000 3700);
FORCEADD RESISTOR..2
R 6
(-9950 4300);
FORCEPROP 0 LAST PACKAGE 0402
J 2
(-10150 4300);
DISPLAY 0.808511 (-10150 4300);
FORCEPROP 1 LAST VALUE 0OHM
J 0
(-10300 4400);
DISPLAY 0.978723 (-10300 4400);
PAINT GREEN (-10300 4400);
FORCEPROP 1 LAST CLS_PN G155-100R0-J0
J 0
(-10086 4043);
DISPLAY 1.212766 (-10086 4043);
PAINT GREEN (-10086 4043);
DISPLAY INVISIBLE (-10086 4043);
FORCEPROP 1 LAST TOLERANCE -
J 0
(-10147 3988);
DISPLAY 1.212766 (-10147 3988);
PAINT GREEN (-10147 3988);
DISPLAY INVISIBLE (-10147 3988);
FORCEPROP 1 LAST PATH I326
J 0
(-10147 4195);
DISPLAY 1.212766 (-10147 4195);
PAINT GREEN (-10147 4195);
DISPLAY INVISIBLE (-10147 4195);
FORCEPROP 2 LAST CDS_LIB passive
R 3
J 2
(-9950 4253);
DISPLAY INVISIBLE (-9950 4253);
FORCEPROP 1 LAST CDS_LMAN_SYM_OUTLINE -50,50,50,-100
J 0
(-9950 4278);
DISPLAY 0.468085 (-9950 4278);
PAINT GREEN (-9950 4278);
DISPLAY INVISIBLE (-9950 4278);
FORCEPROP 1 LAST $LOCATION R494
J 0
(-10300 4200);
DISPLAY 0.978723 (-10300 4200);
PAINT GREEN (-10300 4200);
FORCEPROP 0 LASTPIN (-9950 4200) $PN 1
R 1
J 2
(-9960 4190);
DISPLAY 0.680851 (-9960 4190);
PAINT MONO (-9960 4190);
FORCEPROP 0 LASTPIN (-9950 4450) $PN 2
R 1
J 0
(-9960 4460);
DISPLAY 0.680851 (-9960 4460);
PAINT MONO (-9960 4460);
FORCEPROP 0 LAST CDS_LOCATION R494
J 0
(-10300 4450);
DISPLAY 1.021277 (-10300 4450);
DISPLAY INVISIBLE (-10300 4450);
FORCEPROP 0 LAST $SEC 1
J 0
(-10300 4450);
DISPLAY 0.680851 (-10300 4450);
PAINT MONO (-10300 4450);
DISPLAY INVISIBLE (-10300 4450);
FORCEPROP 0 LAST CDS_SEC 1
J 0
(-10300 4450);
DISPLAY 1.021277 (-10300 4450);
DISPLAY INVISIBLE (-10300 4450);
FORCEADD RESISTOR..2
R 4
(-9700 4050);
FORCEPROP 1 LAST VALUE 1MOHM
J 0
(-9650 4150);
DISPLAY 0.978723 (-9650 4150);
PAINT GREEN (-9650 4150);
FORCEPROP 0 LAST PACKAGE 0402
J 0
(-9650 4050);
DISPLAY 0.808511 (-9650 4050);
FORCEPROP 2 LAST CDS_LIB passive
R 1
J 0
(-9700 4050);
DISPLAY INVISIBLE (-9700 4050);
FORCEPROP 1 LAST CDS_LMAN_SYM_OUTLINE -50,50,50,-100
R 2
J 0
(-9700 4050);
DISPLAY 0.468085 (-9700 4050);
PAINT GREEN (-9700 4050);
DISPLAY INVISIBLE (-9700 4050);
FORCEPROP 1 LAST TOLERANCE 1%
R 2
J 0
(-9503 3795);
DISPLAY 1.212766 (-9503 3795);
PAINT GREEN (-9503 3795);
DISPLAY INVISIBLE (-9503 3795);
FORCEPROP 1 LAST CLS_PN G155-11004-01
R 2
J 0
(-9564 3850);
DISPLAY 1.212766 (-9564 3850);
PAINT GREEN (-9564 3850);
DISPLAY INVISIBLE (-9564 3850);
FORCEPROP 1 LAST PATH I327
R 2
J 0
(-9503 3945);
DISPLAY 1.212766 (-9503 3945);
PAINT GREEN (-9503 3945);
DISPLAY INVISIBLE (-9503 3945);
FORCEPROP 1 LAST $LOCATION R498
J 0
(-9650 3950);
DISPLAY 0.978723 (-9650 3950);
PAINT GREEN (-9650 3950);
FORCEPROP 0 LASTPIN (-9700 3950) $PN 1
R 1
J 2
(-9710 3940);
DISPLAY 0.680851 (-9710 3940);
PAINT MONO (-9710 3940);
FORCEPROP 0 LASTPIN (-9700 4200) $PN 2
R 1
J 0
(-9710 4210);
DISPLAY 0.680851 (-9710 4210);
PAINT MONO (-9710 4210);
FORCEPROP 0 LAST CDS_LOCATION R498
J 0
(-9650 4200);
DISPLAY 1.021277 (-9650 4200);
DISPLAY INVISIBLE (-9650 4200);
FORCEPROP 0 LAST $SEC 1
J 0
(-9650 4200);
DISPLAY 0.680851 (-9650 4200);
PAINT MONO (-9650 4200);
DISPLAY INVISIBLE (-9650 4200);
FORCEPROP 0 LAST CDS_SEC 1
J 0
(-9650 4200);
DISPLAY 1.021277 (-9650 4200);
DISPLAY INVISIBLE (-9650 4200);
FORCEADD CAPACITOR..1
R 1
(-9950 3950);
FORCEPROP 1 LAST VALUE 18PF
J 0
(-10300 3950);
DISPLAY 0.978723 (-10300 3950);
PAINT GREEN (-10300 3950);
FORCEPROP 0 LAST PACKAGE 0201
J 0
(-10300 4050);
DISPLAY 0.808511 (-10300 4050);
FORCEPROP 2 LASTPIN (-9950 4100) SIG_NAME UN$12$CAPACITOR$I328$2
J 0
(-9940 4110);
DISPLAY 0.659574 (-9940 4110);
PAINT MONO (-9940 4110);
DISPLAY INVISIBLE (-9940 4110);
FORCEPROP 1 LAST PATH I328
R 1
J 2
(-10050 3900);
DISPLAY 1.212766 (-10050 3900);
PAINT GREEN (-10050 3900);
DISPLAY INVISIBLE (-10050 3900);
FORCEPROP 2 LAST CDS_LIB passive
J 0
(-9950 3950);
DISPLAY INVISIBLE (-9950 3950);
FORCEPROP 1 LAST CDS_LMAN_SYM_OUTLINE 0,50,50,-50
R 1
J 0
(-9950 3950);
DISPLAY 0.468085 (-9950 3950);
PAINT GREEN (-9950 3950);
DISPLAY INVISIBLE (-9950 3950);
FORCEPROP 1 LAST CLS_PN G104-0A180-FJ
R 1
J 2
(-10050 3900);
DISPLAY 1.212766 (-10050 3900);
PAINT GREEN (-10050 3900);
DISPLAY INVISIBLE (-10050 3900);
FORCEPROP 1 LAST TOLERANCE 5%
R 1
J 2
(-10050 3850);
DISPLAY 1.212766 (-10050 3850);
PAINT GREEN (-10050 3850);
DISPLAY INVISIBLE (-10050 3850);
FORCEPROP 1 LAST $LOCATION C317
J 2
(-10150 3850);
DISPLAY 0.978723 (-10150 3850);
PAINT GREEN (-10150 3850);
FORCEPROP 0 LASTPIN (-9950 3850) $PN 1
R 1
J 2
(-9960 3840);
DISPLAY 0.680851 (-9960 3840);
PAINT MONO (-9960 3840);
FORCEPROP 0 LASTPIN (-9950 4100) $PN 2
R 1
J 0
(-9960 4110);
DISPLAY 0.680851 (-9960 4110);
PAINT MONO (-9960 4110);
FORCEPROP 0 LAST CDS_LOCATION C317
R 1
J 0
(-10300 4100);
DISPLAY 1.021277 (-10300 4100);
DISPLAY INVISIBLE (-10300 4100);
FORCEPROP 0 LAST $SEC 1
R 1
J 0
(-10300 4100);
DISPLAY 0.680851 (-10300 4100);
PAINT MONO (-10300 4100);
DISPLAY INVISIBLE (-10300 4100);
FORCEPROP 0 LAST CDS_SEC 1
R 1
J 0
(-10300 4100);
DISPLAY 1.021277 (-10300 4100);
DISPLAY INVISIBLE (-10300 4100);
FORCEADD GND_SG..1
(-9950 1550);
FORCEPROP 3 LASTPIN (-9900 1600) SIG_NAME SG\g
J 0
(-9890 1610);
DISPLAY 0.659574 (-9890 1610);
PAINT MONO (-9890 1610);
DISPLAY INVISIBLE (-9890 1610);
FORCEPROP 1 LAST HDL_POWER SG
J 1
(-9900 1450);
DISPLAY 0.808511 (-9900 1450);
PAINT GREEN (-9900 1450);
FORCEPROP 2 LAST CDS_LIB cls
J 0
(-9950 1550);
DISPLAY INVISIBLE (-9950 1550);
FORCEPROP 1 LAST CDS_LMAN_SYM_OUTLINE 0,0,100,-50
J 0
(-9950 1550);
DISPLAY 0.468085 (-9950 1550);
PAINT GREEN (-9950 1550);
DISPLAY INVISIBLE (-9950 1550);
FORCEPROP 1 LAST BODY_TYPE PLUMBING
J 0
(-9935 1535);
DISPLAY 0.808511 (-9935 1535);
PAINT GREEN (-9935 1535);
DISPLAY INVISIBLE (-9935 1535);
FORCEPROP 1 LAST PATH I329
J 0
(-9915 1550);
DISPLAY 0.808511 (-9915 1550);
PAINT GREEN (-9915 1550);
DISPLAY INVISIBLE (-9915 1550);
FORCEADD RESISTOR..2
R 6
(-9900 2150);
FORCEPROP 1 LAST VALUE 0OHM
J 0
(-10250 2250);
DISPLAY 0.978723 (-10250 2250);
PAINT GREEN (-10250 2250);
FORCEPROP 0 LAST PACKAGE 0402
J 2
(-10100 2150);
DISPLAY 0.808511 (-10100 2150);
FORCEPROP 1 LAST CLS_PN G155-100R0-J0
J 0
(-10036 1893);
DISPLAY 1.212766 (-10036 1893);
PAINT GREEN (-10036 1893);
DISPLAY INVISIBLE (-10036 1893);
FORCEPROP 1 LAST TOLERANCE -
J 0
(-10097 1838);
DISPLAY 1.212766 (-10097 1838);
PAINT GREEN (-10097 1838);
DISPLAY INVISIBLE (-10097 1838);
FORCEPROP 1 LAST CDS_LMAN_SYM_OUTLINE -50,50,50,-100
J 0
(-9900 2128);
DISPLAY 0.468085 (-9900 2128);
PAINT GREEN (-9900 2128);
DISPLAY INVISIBLE (-9900 2128);
FORCEPROP 2 LAST CDS_LIB passive
R 3
J 2
(-9900 2103);
DISPLAY INVISIBLE (-9900 2103);
FORCEPROP 1 LAST PATH I330
J 0
(-10097 2045);
DISPLAY 1.212766 (-10097 2045);
PAINT GREEN (-10097 2045);
DISPLAY INVISIBLE (-10097 2045);
FORCEPROP 1 LAST $LOCATION R495
J 0
(-10250 2050);
DISPLAY 0.978723 (-10250 2050);
PAINT GREEN (-10250 2050);
FORCEPROP 0 LASTPIN (-9900 2050) $PN 1
R 1
J 2
(-9910 2040);
DISPLAY 0.680851 (-9910 2040);
PAINT MONO (-9910 2040);
FORCEPROP 0 LASTPIN (-9900 2300) $PN 2
R 1
J 0
(-9910 2310);
DISPLAY 0.680851 (-9910 2310);
PAINT MONO (-9910 2310);
FORCEPROP 0 LAST CDS_LOCATION R495
J 0
(-10250 2300);
DISPLAY 1.021277 (-10250 2300);
DISPLAY INVISIBLE (-10250 2300);
FORCEPROP 0 LAST $SEC 1
J 0
(-10250 2300);
DISPLAY 0.680851 (-10250 2300);
PAINT MONO (-10250 2300);
DISPLAY INVISIBLE (-10250 2300);
FORCEPROP 0 LAST CDS_SEC 1
J 0
(-10250 2300);
DISPLAY 1.021277 (-10250 2300);
DISPLAY INVISIBLE (-10250 2300);
FORCEADD RESISTOR..2
R 4
(-9650 1900);
FORCEPROP 1 LAST VALUE 1MOHM
J 0
(-9600 2000);
DISPLAY 0.978723 (-9600 2000);
PAINT GREEN (-9600 2000);
FORCEPROP 0 LAST PACKAGE 0402
J 0
(-9600 1900);
DISPLAY 0.808511 (-9600 1900);
FORCEPROP 1 LAST CLS_PN G155-11004-01
R 2
J 0
(-9514 1700);
DISPLAY 1.212766 (-9514 1700);
PAINT GREEN (-9514 1700);
DISPLAY INVISIBLE (-9514 1700);
FORCEPROP 1 LAST TOLERANCE 1%
R 2
J 0
(-9453 1645);
DISPLAY 1.212766 (-9453 1645);
PAINT GREEN (-9453 1645);
DISPLAY INVISIBLE (-9453 1645);
FORCEPROP 1 LAST CDS_LMAN_SYM_OUTLINE -50,50,50,-100
R 2
J 0
(-9650 1900);
DISPLAY 0.468085 (-9650 1900);
PAINT GREEN (-9650 1900);
DISPLAY INVISIBLE (-9650 1900);
FORCEPROP 2 LAST CDS_LIB passive
R 1
J 0
(-9650 1900);
DISPLAY INVISIBLE (-9650 1900);
FORCEPROP 1 LAST PATH I331
R 2
J 0
(-9453 1795);
DISPLAY 1.212766 (-9453 1795);
PAINT GREEN (-9453 1795);
DISPLAY INVISIBLE (-9453 1795);
FORCEPROP 1 LAST $LOCATION R499
J 0
(-9600 1800);
DISPLAY 0.978723 (-9600 1800);
PAINT GREEN (-9600 1800);
FORCEPROP 0 LASTPIN (-9650 1800) $PN 1
R 1
J 2
(-9660 1790);
DISPLAY 0.680851 (-9660 1790);
PAINT MONO (-9660 1790);
FORCEPROP 0 LASTPIN (-9650 2050) $PN 2
R 1
J 0
(-9660 2060);
DISPLAY 0.680851 (-9660 2060);
PAINT MONO (-9660 2060);
FORCEPROP 0 LAST CDS_LOCATION R499
J 0
(-9600 2050);
DISPLAY 1.021277 (-9600 2050);
DISPLAY INVISIBLE (-9600 2050);
FORCEPROP 0 LAST $SEC 1
J 0
(-9600 2050);
DISPLAY 0.680851 (-9600 2050);
PAINT MONO (-9600 2050);
DISPLAY INVISIBLE (-9600 2050);
FORCEPROP 0 LAST CDS_SEC 1
J 0
(-9600 2050);
DISPLAY 1.021277 (-9600 2050);
DISPLAY INVISIBLE (-9600 2050);
FORCEADD CAPACITOR..1
R 1
(-9900 1800);
FORCEPROP 1 LAST VALUE 18PF
J 0
(-10250 1800);
DISPLAY 0.978723 (-10250 1800);
PAINT GREEN (-10250 1800);
FORCEPROP 0 LAST PACKAGE 0201
J 0
(-10250 1900);
DISPLAY 0.808511 (-10250 1900);
FORCEPROP 1 LAST TOLERANCE 5%
R 1
J 2
(-10000 1700);
DISPLAY 1.212766 (-10000 1700);
PAINT GREEN (-10000 1700);
DISPLAY INVISIBLE (-10000 1700);
FORCEPROP 1 LAST CLS_PN G104-0A180-FJ
R 1
J 2
(-10000 1750);
DISPLAY 1.212766 (-10000 1750);
PAINT GREEN (-10000 1750);
DISPLAY INVISIBLE (-10000 1750);
FORCEPROP 1 LAST CDS_LMAN_SYM_OUTLINE 0,50,50,-50
R 1
J 0
(-9900 1800);
DISPLAY 0.468085 (-9900 1800);
PAINT GREEN (-9900 1800);
DISPLAY INVISIBLE (-9900 1800);
FORCEPROP 2 LAST CDS_LIB passive
J 0
(-9900 1800);
DISPLAY INVISIBLE (-9900 1800);
FORCEPROP 1 LAST PATH I332
R 1
J 2
(-10000 1750);
DISPLAY 1.212766 (-10000 1750);
PAINT GREEN (-10000 1750);
DISPLAY INVISIBLE (-10000 1750);
FORCEPROP 2 LASTPIN (-9900 1950) SIG_NAME UN$12$CAPACITOR$I332$2
J 0
(-9890 1960);
DISPLAY 0.659574 (-9890 1960);
PAINT MONO (-9890 1960);
DISPLAY INVISIBLE (-9890 1960);
FORCEPROP 1 LAST $LOCATION C318
J 2
(-10100 1700);
DISPLAY 0.978723 (-10100 1700);
PAINT GREEN (-10100 1700);
FORCEPROP 0 LASTPIN (-9900 1700) $PN 1
R 1
J 2
(-9910 1690);
DISPLAY 0.680851 (-9910 1690);
PAINT MONO (-9910 1690);
FORCEPROP 0 LASTPIN (-9900 1950) $PN 2
R 1
J 0
(-9910 1960);
DISPLAY 0.680851 (-9910 1960);
PAINT MONO (-9910 1960);
FORCEPROP 0 LAST CDS_LOCATION C318
R 1
J 0
(-10250 1950);
DISPLAY 1.021277 (-10250 1950);
DISPLAY INVISIBLE (-10250 1950);
FORCEPROP 0 LAST $SEC 1
R 1
J 0
(-10250 1950);
DISPLAY 0.680851 (-10250 1950);
PAINT MONO (-10250 1950);
DISPLAY INVISIBLE (-10250 1950);
FORCEPROP 0 LAST CDS_SEC 1
R 1
J 0
(-10250 1950);
DISPLAY 1.021277 (-10250 1950);
DISPLAY INVISIBLE (-10250 1950);
FORCEADD GND_SG..1
(-3750 7500);
FORCEPROP 3 LASTPIN (-3700 7550) SIG_NAME SG\g
J 0
(-3690 7560);
DISPLAY 0.659574 (-3690 7560);
PAINT MONO (-3690 7560);
DISPLAY INVISIBLE (-3690 7560);
FORCEPROP 1 LAST HDL_POWER SG
J 1
(-3700 7400);
DISPLAY 0.808511 (-3700 7400);
PAINT GREEN (-3700 7400);
FORCEPROP 1 LAST PATH I41
J 0
(-3715 7500);
DISPLAY 0.808511 (-3715 7500);
PAINT GREEN (-3715 7500);
DISPLAY INVISIBLE (-3715 7500);
FORCEPROP 1 LAST BODY_TYPE PLUMBING
J 0
(-3735 7485);
DISPLAY 0.808511 (-3735 7485);
PAINT GREEN (-3735 7485);
DISPLAY INVISIBLE (-3735 7485);
FORCEPROP 2 LAST CDS_LIB cls
J 0
(-3750 7500);
DISPLAY INVISIBLE (-3750 7500);
FORCEPROP 1 LAST CDS_LMAN_SYM_OUTLINE 0,0,100,-50
J 0
(-3750 7500);
DISPLAY 0.468085 (-3750 7500);
PAINT GREEN (-3750 7500);
DISPLAY INVISIBLE (-3750 7500);
FORCEADD DIODE_4_V1..1
R 1
(-3800 7700);
FORCEPROP 1 LAST CLS_PN G122-10123-01
J 0
(-4600 7800);
DISPLAY 1.212766 (-4600 7800);
PAINT GREEN (-4600 7800);
FORCEPROP 0 LAST PART_NUMBER SR3.3.TCT
J 0
(-4600 7900);
DISPLAY 1.021277 (-4600 7900);
FORCEPROP 1 LAST PATH I42
R 1
J 0
(-3850 7750);
DISPLAY 1.212766 (-3850 7750);
PAINT GREEN (-3850 7750);
DISPLAY INVISIBLE (-3850 7750);
FORCEPROP 2 LAST CDS_LIB discrete
R 1
J 0
(-3800 7700);
DISPLAY INVISIBLE (-3800 7700);
FORCEPROP 1 LAST CDS_LMAN_SYM_OUTLINE 0,0,400,-600
R 1
J 0
(-3800 7700);
DISPLAY 0.468085 (-3800 7700);
PAINT GREEN (-3800 7700);
DISPLAY INVISIBLE (-3800 7700);
FORCEPROP 1 LAST $LOCATION CR5
J 0
(-4000 7700);
DISPLAY 1.212766 (-4000 7700);
PAINT GREEN (-4000 7700);
FORCEPROP 0 LASTPIN (-3700 7600) $PN 1
R 1
J 2
(-3710 7590);
DISPLAY 0.680851 (-3710 7590);
PAINT MONO (-3710 7590);
FORCEPROP 0 LASTPIN (-3400 7600) $PN 2
R 1
J 2
(-3410 7590);
DISPLAY 0.680851 (-3410 7590);
PAINT MONO (-3410 7590);
FORCEPROP 0 LASTPIN (-3450 8200) $PN 3
R 1
J 0
(-3460 8210);
DISPLAY 0.680851 (-3460 8210);
PAINT MONO (-3460 8210);
FORCEPROP 0 LASTPIN (-3700 8200) $PN 4
R 1
J 0
(-3710 8210);
DISPLAY 0.680851 (-3710 8210);
PAINT MONO (-3710 8210);
FORCEPROP 0 LAST CDS_LOCATION CR5
R 1
J 0
(-4550 8100);
DISPLAY 1.021277 (-4550 8100);
DISPLAY INVISIBLE (-4550 8100);
FORCEPROP 0 LAST $SEC 1
R 1
J 0
(-4550 8100);
DISPLAY 0.680851 (-4550 8100);
PAINT MONO (-4550 8100);
DISPLAY INVISIBLE (-4550 8100);
FORCEPROP 0 LAST CDS_SEC 1
R 1
J 0
(-4550 8100);
DISPLAY 1.021277 (-4550 8100);
DISPLAY INVISIBLE (-4550 8100);
FORCEADD GND_SG..1
(-1950 8550);
FORCEPROP 3 LASTPIN (-1900 8600) SIG_NAME SG\g
J 0
(-1890 8610);
DISPLAY 0.659574 (-1890 8610);
PAINT MONO (-1890 8610);
DISPLAY INVISIBLE (-1890 8610);
FORCEPROP 1 LAST HDL_POWER SG
J 1
(-1900 8450);
DISPLAY 0.808511 (-1900 8450);
PAINT GREEN (-1900 8450);
FORCEPROP 1 LAST PATH I55
J 0
(-1915 8550);
DISPLAY 0.808511 (-1915 8550);
PAINT GREEN (-1915 8550);
DISPLAY INVISIBLE (-1915 8550);
FORCEPROP 1 LAST BODY_TYPE PLUMBING
J 0
(-1935 8535);
DISPLAY 0.808511 (-1935 8535);
PAINT GREEN (-1935 8535);
DISPLAY INVISIBLE (-1935 8535);
FORCEPROP 1 LAST CDS_LMAN_SYM_OUTLINE 0,0,100,-50
J 0
(-1950 8550);
DISPLAY 0.468085 (-1950 8550);
PAINT GREEN (-1950 8550);
DISPLAY INVISIBLE (-1950 8550);
FORCEPROP 2 LAST CDS_LIB cls
J 0
(-1950 8550);
DISPLAY INVISIBLE (-1950 8550);
FORCEADD OFFPAGE_IN..1
R 6
(-12950 9050);
FORCEPROP 2 LAST $XR0 11F5> 
J 0
(-13133 9050);
DISPLAY 0.638298 (-13133 9050);
PAINT MONO (-13133 9050);
FORCEPROP 1 LAST BODY_TYPE COMMENT
J 0
(-12940 8915);
DISPLAY 0.808511 (-12940 8915);
PAINT GREEN (-12940 8915);
DISPLAY INVISIBLE (-12940 8915);
FORCEPROP 1 LAST CDS_LMAN_SYM_OUTLINE -50,50,50,-50
J 0
(-12950 9050);
DISPLAY 0.468085 (-12950 9050);
PAINT GREEN (-12950 9050);
DISPLAY INVISIBLE (-12950 9050);
FORCEPROP 2 LAST CDS_LIB cls
J 0
(-12950 9050);
DISPLAY INVISIBLE (-12950 9050);
FORCEPROP 1 LAST OFFPAGE TRUE
J 0
(-12940 8995);
DISPLAY 0.808511 (-12940 8995);
PAINT GREEN (-12940 8995);
DISPLAY INVISIBLE (-12940 8995);
FORCEPROP 2 LAST PATH I61
J 0
(-13100 9100);
DISPLAY 1.021277 (-13100 9100);
DISPLAY INVISIBLE (-13100 9100);
FORCEADD RESISTOR..2
R 3
(-10750 9050);
FORCEPROP 1 LAST VALUE 100OHM
J 2
(-10150 9050);
DISPLAY 1.212766 (-10150 9050);
PAINT GREEN (-10150 9050);
FORCEPROP 0 LAST PACKAGE 0402
J 0
(-10800 9100);
DISPLAY 0.808511 (-10800 9100);
FORCEPROP 1 LAST CLS_PN G155-11000-01
R 1
J 2
(-10950 9186);
DISPLAY 1.212766 (-10950 9186);
PAINT GREEN (-10950 9186);
DISPLAY INVISIBLE (-10950 9186);
FORCEPROP 1 LAST TOLERANCE 1%
R 1
J 2
(-11005 9247);
DISPLAY 1.212766 (-11005 9247);
PAINT GREEN (-11005 9247);
DISPLAY INVISIBLE (-11005 9247);
FORCEPROP 2 LAST CDS_LIB passive
J 0
(-10750 9050);
DISPLAY INVISIBLE (-10750 9050);
FORCEPROP 1 LAST CDS_LMAN_SYM_OUTLINE -50,50,50,-100
R 1
J 2
(-10750 9050);
DISPLAY 0.468085 (-10750 9050);
PAINT GREEN (-10750 9050);
DISPLAY INVISIBLE (-10750 9050);
FORCEPROP 1 LAST PATH I63
R 1
J 2
(-10855 9247);
DISPLAY 1.212766 (-10855 9247);
PAINT GREEN (-10855 9247);
DISPLAY INVISIBLE (-10855 9247);
FORCEPROP 1 LAST $LOCATION R156
J 2
(-10900 9050);
DISPLAY 1.212766 (-10900 9050);
PAINT GREEN (-10900 9050);
FORCEPROP 0 LASTPIN (-10850 9050) $PN 1
J 2
(-10860 9060);
DISPLAY 0.680851 (-10860 9060);
PAINT MONO (-10860 9060);
FORCEPROP 0 LASTPIN (-10600 9050) $PN 2
J 0
(-10590 9060);
DISPLAY 0.680851 (-10590 9060);
PAINT MONO (-10590 9060);
FORCEPROP 0 LAST CDS_LOCATION R156
R 1
J 0
(-10200 9200);
DISPLAY 1.021277 (-10200 9200);
DISPLAY INVISIBLE (-10200 9200);
FORCEPROP 0 LAST $SEC 1
R 1
J 0
(-10200 9200);
DISPLAY 0.680851 (-10200 9200);
PAINT MONO (-10200 9200);
DISPLAY INVISIBLE (-10200 9200);
FORCEPROP 0 LAST CDS_SEC 1
R 1
J 0
(-10200 9200);
DISPLAY 1.021277 (-10200 9200);
DISPLAY INVISIBLE (-10200 9200);
FORCEADD OFFPAGE_IN..1
R 6
(-12950 9150);
FORCEPROP 2 LAST $XR0 12D5> 
J 0
(-13133 9150);
DISPLAY 0.638298 (-13133 9150);
PAINT MONO (-13133 9150);
FORCEPROP 2 LAST $XR1 25E6<> 
J 0
(-13343 9150);
DISPLAY 0.638298 (-13343 9150);
PAINT MONO (-13343 9150);
FORCEPROP 2 LAST CDS_LIB cls
J 0
(-12950 9150);
DISPLAY INVISIBLE (-12950 9150);
FORCEPROP 1 LAST CDS_LMAN_SYM_OUTLINE -50,50,50,-50
J 0
(-12950 9150);
DISPLAY 0.468085 (-12950 9150);
PAINT GREEN (-12950 9150);
DISPLAY INVISIBLE (-12950 9150);
FORCEPROP 1 LAST BODY_TYPE COMMENT
J 0
(-12940 9015);
DISPLAY 0.808511 (-12940 9015);
PAINT GREEN (-12940 9015);
DISPLAY INVISIBLE (-12940 9015);
FORCEPROP 1 LAST OFFPAGE TRUE
J 0
(-12940 9095);
DISPLAY 0.808511 (-12940 9095);
PAINT GREEN (-12940 9095);
DISPLAY INVISIBLE (-12940 9095);
FORCEPROP 2 LAST PATH I79
J 0
(-12900 9250);
DISPLAY 1.021277 (-12900 9250);
DISPLAY INVISIBLE (-12900 9250);
FORCEADD RESISTOR..2
R 1
(-10750 9500);
FORCEPROP 0 LAST PACKAGE 0402
J 0
(-10800 9550);
DISPLAY 1.021277 (-10800 9550);
FORCEPROP 1 LAST VALUE 4.7KOHM
J 0
(-10500 9500);
DISPLAY 1.212766 (-10500 9500);
PAINT GREEN (-10500 9500);
FORCEPROP 1 LAST PATH I88
R 1
J 0
(-10855 9303);
DISPLAY 1.212766 (-10855 9303);
PAINT GREEN (-10855 9303);
DISPLAY INVISIBLE (-10855 9303);
FORCEPROP 2 LAST CDS_LIB passive
J 0
(-10750 9500);
DISPLAY INVISIBLE (-10750 9500);
FORCEPROP 1 LAST CDS_LMAN_SYM_OUTLINE -50,50,50,-100
R 1
J 0
(-10750 9500);
DISPLAY 0.468085 (-10750 9500);
PAINT GREEN (-10750 9500);
DISPLAY INVISIBLE (-10750 9500);
FORCEPROP 1 LAST CLS_PN G155-14701-01
R 1
J 0
(-10950 9364);
DISPLAY 1.212766 (-10950 9364);
PAINT GREEN (-10950 9364);
DISPLAY INVISIBLE (-10950 9364);
FORCEPROP 1 LAST TOLERANCE 1%
R 1
J 0
(-11005 9303);
DISPLAY 1.212766 (-11005 9303);
PAINT GREEN (-11005 9303);
DISPLAY INVISIBLE (-11005 9303);
FORCEPROP 1 LAST $LOCATION R365
J 0
(-11150 9500);
DISPLAY 1.212766 (-11150 9500);
PAINT GREEN (-11150 9500);
FORCEPROP 0 LASTPIN (-10850 9500) $PN 1
J 2
(-10860 9510);
DISPLAY 0.680851 (-10860 9510);
PAINT MONO (-10860 9510);
FORCEPROP 0 LASTPIN (-10600 9500) $PN 2
J 0
(-10590 9510);
DISPLAY 0.680851 (-10590 9510);
PAINT MONO (-10590 9510);
FORCEPROP 0 LAST CDS_LOCATION R365
R 1
J 0
(-10550 9600);
DISPLAY 1.021277 (-10550 9600);
DISPLAY INVISIBLE (-10550 9600);
FORCEPROP 0 LAST $SEC 1
R 1
J 0
(-10550 9600);
DISPLAY 0.680851 (-10550 9600);
PAINT MONO (-10550 9600);
DISPLAY INVISIBLE (-10550 9600);
FORCEPROP 0 LAST CDS_SEC 1
R 1
J 0
(-10550 9600);
DISPLAY 1.021277 (-10550 9600);
DISPLAY INVISIBLE (-10550 9600);
FORCEADD VCC..1
(-11400 9650);
FORCEPROP 3 LASTPIN (-11350 9600) SIG_NAME XP3R3V_FPGA\g
J 0
(-11340 9610);
DISPLAY 0.659574 (-11340 9610);
PAINT MONO (-11340 9610);
DISPLAY INVISIBLE (-11340 9610);
FORCEPROP 0 LAST VOLTAGE 3.3V
J 0
(-11650 9800);
DISPLAY 1.021277 (-11650 9800);
DISPLAY BOTH (-11650 9800);
FORCEPROP 1 LAST HDL_POWER XP3R3V_FPGA
J 1
(-11345 9705);
DISPLAY 1.021277 (-11345 9705);
PAINT GREEN (-11345 9705);
FORCEPROP 1 LAST PATH I89
J 0
(-11365 9740);
DISPLAY 0.808511 (-11365 9740);
PAINT GREEN (-11365 9740);
DISPLAY INVISIBLE (-11365 9740);
FORCEPROP 1 LAST BODY_TYPE PLUMBING
J 0
(-11445 9607);
DISPLAY 0.340426 (-11445 9607);
PAINT GREEN (-11445 9607);
DISPLAY INVISIBLE (-11445 9607);
FORCEPROP 1 LAST CDS_LMAN_SYM_OUTLINE -250,250,250,-250
J 0
(-11400 9650);
DISPLAY 0.468085 (-11400 9650);
PAINT GREEN (-11400 9650);
DISPLAY INVISIBLE (-11400 9650);
FORCEPROP 2 LAST CDS_LIB cls
J 0
(-11400 9650);
DISPLAY INVISIBLE (-11400 9650);
FORCEADD SHEET_A1..1
(550 -150);
FORCEPROP 2 LAST CUSTOM_TXT_CDS <XR_PAGE_TITLE>
J 0
(-15020 11200);
DISPLAY 0.638298 (-15020 11200);
PAINT PINK (-15020 11200);
FORCEPROP 1 LAST CUSTOM_TXT_CDS <DOCNO>
J 0
(-1500 235);
DISPLAY 0.978723 (-1500 235);
FORCEPROP 1 LAST CUSTOM_TXT_CDS <CON_PAGE_NUM>
J 0
(-1605 -100);
DISPLAY 0.978723 (-1605 -100);
FORCEPROP 1 LAST CUSTOM_TXT_CDS <DATE>
J 0
(-150 25);
DISPLAY 0.978723 (-150 25);
FORCEPROP 1 LAST CUSTOM_TXT_CDS <TITLE>
J 1
(-1235 480);
DISPLAY 0.978723 (-1235 480);
FORCEPROP 1 LAST CUSTOM_TXT_CDS <DESIGNER>
J 0
(-150 450);
DISPLAY 0.978723 (-150 450);
FORCEPROP 1 LAST CUSTOM_TXT_CDS <CON_TOTAL_PAGES>
J 0
(-1295 -100);
DISPLAY 0.808511 (-1295 -100);
FORCEPROP 1 LAST CUSTOM_TXT_CDS <ASSY_PN>
J 0
(-1500 25);
DISPLAY 0.978723 (-1500 25);
FORCEPROP 1 LAST CUSTOM_TXT_CDS <DOCREV>
J 0
(-150 225);
DISPLAY 0.978723 (-150 225);
FORCEPROP 1 LAST TITLE SMA_CONN
J 0
(-1950 700);
DISPLAY 3.042553 (-1950 700);
PAINT GREEN (-1950 700);
FORCEPROP 1 LAST COMMENT_BODY TRUE
J 0
(560 -95);
DISPLAY 0.808511 (560 -95);
DISPLAY INVISIBLE (560 -95);
FORCEPROP 2 LAST PAGE_BORDER TRUE
J 0
(-15020 11200);
DISPLAY 0.638298 (-15020 11200);
PAINT PINK (-15020 11200);
DISPLAY INVISIBLE (-15020 11200);
FORCEPROP 1 LAST CDS_LMAN_SYM_OUTLINE -15850,11500,200,-200
J 0
(550 -150);
DISPLAY 0.468085 (550 -150);
PAINT GREEN (550 -150);
DISPLAY INVISIBLE (550 -150);
FORCEPROP 2 LAST CDS_LIB cls
J 0
(550 -150);
DISPLAY INVISIBLE (550 -150);
FORCEPROP 2 LAST CDS_XR_PAGE_TITLE CR-23 : @TIMECARD_LIB.TIMECARD(SCH_1):PAGE23
J 0
(-15020 11200);
DISPLAY 0.638298 (-15020 11200);
PAINT PINK (-15020 11200);
DISPLAY INVISIBLE (-15020 11200);
WIRE 16 -1 (-11350 9600)(-11350 9500);
WIRE 16 -1 (-1900 8700)(-1900 8600);
WIRE 16 -1 (-2050 8700)(-1900 8700);
WIRE 16 -1 (-1900 8850)(-1900 8700);
WIRE 16 -1 (-3700 7600)(-3700 7550);
WIRE 16 -1 (-9900 1650)(-9900 1600);
WIRE 16 -1 (-9650 1650)(-9900 1650);
WIRE 16 -1 (-9900 1700)(-9900 1650);
WIRE 16 -1 (-9950 3800)(-9950 3750);
WIRE 16 -1 (-9700 3800)(-9950 3800);
WIRE 16 -1 (-9950 3850)(-9950 3800);
WIRE 16 -1 (-9950 5950)(-9950 5900);
WIRE 16 -1 (-9950 6000)(-9950 5950);
WIRE 16 -1 (-9700 5950)(-9950 5950);
WIRE 16 -1 (-10000 8100)(-10000 8050);
WIRE 16 -1 (-9750 8100)(-10000 8100);
WIRE 16 -1 (-10000 8150)(-10000 8100);
WIRE 16 -1 (-1800 2250)(-1800 2150);
WIRE 16 -1 (-1950 2250)(-1800 2250);
WIRE 16 -1 (-1800 2400)(-1800 2250);
WIRE 16 -1 (-2800 2250)(-2800 2150);
WIRE 16 -1 (-2650 2250)(-2800 2250);
WIRE 16 -1 (-2800 2400)(-2800 2250);
WIRE 16 -1 (-1850 4400)(-1850 4300);
WIRE 16 -1 (-1850 4550)(-1850 4400);
WIRE 16 -1 (-2000 4400)(-1850 4400);
WIRE 16 -1 (-2850 4400)(-2850 4300);
WIRE 16 -1 (-2850 4550)(-2850 4400);
WIRE 16 -1 (-2700 4400)(-2850 4400);
WIRE 16 -1 (-1850 6550)(-1850 6450);
WIRE 16 -1 (-2000 6550)(-1850 6550);
WIRE 16 -1 (-1850 6700)(-1850 6550);
WIRE 16 -1 (-2850 6550)(-2850 6450);
WIRE 16 -1 (-2850 6700)(-2850 6550);
WIRE 16 -1 (-2700 6550)(-2850 6550);
WIRE 16 -1 (-2900 8700)(-2900 8600);
WIRE 16 -1 (-2900 8850)(-2900 8700);
WIRE 16 -1 (-2750 8700)(-2900 8700);
WIRE 16 -1 (-11250 3150)(-11250 3050);
WIRE 16 -1 (-8650 2000)(-8650 2050);
WIRE 16 -1 (-8350 2800)(-8350 2700);
WIRE 16 -1 (-8700 4150)(-8700 4200);
WIRE 16 -1 (-11300 5300)(-11300 5200);
WIRE 16 -1 (-8400 4950)(-8400 4850);
WIRE 16 -1 (-11300 7400)(-11300 7350);
WIRE 16 -1 (-8700 6300)(-8700 6350);
WIRE 16 -1 (-8400 7100)(-8400 7000);
WIRE 16 -1 (-8750 8450)(-8750 8500);
WIRE 16 -1 (-8450 9250)(-8450 9150);
WIRE 16 -1 (-3650 3250)(-3650 3150);
WIRE 16 -1 (-11250 9400)(-10850 9400);
WIRE 16 -1 (-11250 9400)(-11250 9500);
WIRE 16 -1 (-10850 9500)(-11250 9500);
WIRE 16 -1 (-11350 9500)(-11250 9500);
WIRE 16 -1 (-1900 8850)(-2050 8850);
WIRE 16 -1 (-9650 1800)(-9650 1650);
WIRE 16 -1 (-9700 3950)(-9700 3800);
WIRE 16 -1 (-9700 6100)(-9700 5950);
WIRE 16 -1 (-9750 8250)(-9750 8100);
WIRE 16 -1 (-1800 2400)(-1950 2400);
WIRE 16 -1 (-2800 2400)(-2650 2400);
WIRE 16 -1 (-1850 4550)(-2000 4550);
WIRE 16 -1 (-2850 4550)(-2700 4550);
WIRE 16 -1 (-1850 6700)(-2000 6700);
WIRE 16 -1 (-2850 6700)(-2700 6700);
WIRE 16 -1 (-2900 8850)(-2750 8850);
WIRE 16 -1 (-11150 2950)(-10750 2950);
WIRE 16 -1 (-11150 2950)(-11150 3050);
WIRE 16 -1 (-10750 3050)(-11150 3050);
WIRE 16 -1 (-11250 3050)(-11150 3050);
WIRE 16 -1 (-8350 2150)(-8350 2050);
WIRE 16 -1 (-8850 2400)(-8650 2400);
WIRE 16 -1 (-8650 2400)(-8650 2050);
WIRE 16 -1 (-8650 2050)(-8350 2050);
WIRE 16 -1 (-8850 2700)(-8350 2700);
WIRE 16 -1 (-8350 2700)(-8350 2400);
WIRE 16 -1 (-8900 4550)(-8700 4550);
WIRE 16 -1 (-8400 4300)(-8400 4200);
WIRE 16 -1 (-8700 4200)(-8400 4200);
WIRE 16 -1 (-8700 4550)(-8700 4200);
WIRE 16 -1 (-11200 5100)(-10800 5100);
WIRE 16 -1 (-11200 5100)(-11200 5200);
WIRE 16 -1 (-10800 5200)(-11200 5200);
WIRE 16 -1 (-11300 5200)(-11200 5200);
WIRE 16 -1 (-8900 4850)(-8400 4850);
WIRE 16 -1 (-8400 4850)(-8400 4550);
WIRE 16 -1 (-11200 7250)(-10800 7250);
WIRE 16 -1 (-11200 7250)(-11200 7350);
WIRE 16 -1 (-10800 7350)(-11200 7350);
WIRE 16 -1 (-11300 7350)(-11200 7350);
WIRE 16 -1 (-8900 6700)(-8700 6700);
WIRE 16 -1 (-8400 6350)(-8400 6450);
WIRE 16 -1 (-8700 6350)(-8400 6350);
WIRE 16 -1 (-8700 6700)(-8700 6350);
WIRE 16 -1 (-8900 7000)(-8400 7000);
WIRE 16 -1 (-8400 7000)(-8400 6700);
WIRE 16 -1 (-8450 8500)(-8450 8600);
WIRE 16 -1 (-8950 8850)(-8750 8850);
WIRE 16 -1 (-8750 8850)(-8750 8500);
WIRE 16 -1 (-8750 8500)(-8450 8500);
WIRE 16 -1 (-8950 9150)(-8450 9150);
WIRE 16 -1 (-8450 9150)(-8450 8850);
WIRE 16 -1 (-12900 4750)(-10800 4750);
FORCEPROP 2 LAST SIG_NAME ANT1_OUT
J 0
(-12810 4760);
DISPLAY 1.021277 (-12810 4760);
WIRE 16 -1 (-9750 3050)(-10500 3050);
WIRE 16 -1 (-9750 2700)(-12900 2700);
FORCEPROP 2 LAST SIG_NAME SMA2_SIG_OUT_BF_EN_N
J 0
(-12810 2710);
DISPLAY 1.021277 (-12810 2710);
WIRE 16 -1 (-9750 3050)(-9750 2700);
WIRE 16 -1 (-9550 2700)(-9750 2700);
WIRE 16 -1 (-10500 2950)(-9800 2950);
WIRE 16 -1 (-9800 2950)(-9800 2400);
WIRE 16 -1 (-9550 2400)(-9800 2400);
WIRE 16 -1 (-12900 2400)(-9800 2400);
FORCEPROP 2 LAST SIG_NAME SMA2_SIG_IN_BF_EN_N
J 0
(-12810 2410);
DISPLAY 1.021277 (-12810 2410);
WIRE 16 -1 (-9800 9150)(-12900 9150);
FORCEPROP 2 LAST SIG_NAME SMA3_SIG_OUT_BF_EN_N
J 0
(-12810 9160);
DISPLAY 1.021277 (-12810 9160);
WIRE 16 -1 (-9650 9150)(-9800 9150);
WIRE 16 -1 (-9800 9500)(-10600 9500);
WIRE 16 -1 (-9800 9500)(-9800 9150);
WIRE 16 -1 (-9800 4850)(-12900 4850);
FORCEPROP 2 LAST SIG_NAME SMA1_SIG_OUT_BF_EN_N
J 0
(-12810 4860);
DISPLAY 1.021277 (-12810 4860);
WIRE 16 -1 (-9600 4850)(-9800 4850);
WIRE 16 -1 (-9800 5200)(-10550 5200);
WIRE 16 -1 (-9800 5200)(-9800 4850);
WIRE 16 -1 (-3350 3250)(-3350 2600);
WIRE 16 -1 (-2650 2600)(-3350 2600);
WIRE 16 -1 (-6150 2600)(-3350 2600);
FORCEPROP 2 LAST SIG_NAME SMA2_SIG_IO_CONN
J 0
(-5260 2610);
DISPLAY 1.021277 (-5260 2610);
WIRE 16 -1 (-3400 3850)(-3400 4750);
WIRE 16 -1 (-2700 4750)(-3400 4750);
WIRE 16 -1 (-6200 4750)(-3400 4750);
FORCEPROP 2 LAST SIG_NAME SMA1_SIG_IO_CONN
J 0
(-5310 4760);
DISPLAY 1.021277 (-5310 4760);
WIRE 16 -1 (-10550 7250)(-9800 7250);
WIRE 16 -1 (-9600 6700)(-9800 6700);
WIRE 16 -1 (-9800 7250)(-9800 6700);
WIRE 16 -1 (-12900 6700)(-9800 6700);
FORCEPROP 2 LAST SIG_NAME SMA4_SIG_IN_BF_EN_N
J 0
(-12810 6710);
DISPLAY 1.021277 (-12810 6710);
WIRE 16 -1 (-9750 7000)(-12900 7000);
FORCEPROP 2 LAST SIG_NAME SMA4_SIG_OUT_BF_EN_N
J 0
(-12810 7010);
DISPLAY 1.021277 (-12810 7010);
WIRE 16 -1 (-9600 7000)(-9750 7000);
WIRE 16 -1 (-9750 7350)(-10550 7350);
WIRE 16 -1 (-9750 7350)(-9750 7000);
WIRE 16 -1 (-12900 6900)(-10800 6900);
FORCEPROP 2 LAST SIG_NAME ANT4_OUT
J 0
(-12810 6910);
DISPLAY 1.021277 (-12810 6910);
WIRE 16 -1 (-10550 5100)(-9850 5100);
WIRE 16 -1 (-9850 5100)(-9850 4550);
WIRE 16 -1 (-9600 4550)(-9850 4550);
WIRE 16 -1 (-12900 4550)(-9850 4550);
FORCEPROP 2 LAST SIG_NAME SMA1_SIG_IN_BF_EN_N
J 0
(-12810 4560);
DISPLAY 1.021277 (-12810 4560);
WIRE 16 -1 (-12900 9050)(-10850 9050);
FORCEPROP 2 LAST SIG_NAME ANT3_OUT
J 0
(-12810 9060);
DISPLAY 1.021277 (-12810 9060);
WIRE 16 -1 (-10600 9400)(-9850 9400);
WIRE 16 -1 (-9650 8850)(-9850 8850);
WIRE 16 -1 (-9850 9400)(-9850 8850);
WIRE 16 -1 (-12900 8850)(-9850 8850);
FORCEPROP 2 LAST SIG_NAME SMA3_SIG_IN_BF_EN_N
J 0
(-12810 8860);
DISPLAY 1.021277 (-12810 8860);
WIRE 16 -1 (-10550 6900)(-9950 6900);
WIRE 16 -1 (-9950 6900)(-9600 6900);
WIRE 16 -1 (-9950 6600)(-9950 6900);
WIRE 16 -1 (-9650 8950)(-9750 8950);
WIRE 16 -1 (-9750 8500)(-9750 8650);
WIRE 16 -1 (-9750 8950)(-9750 8650);
WIRE 16 -1 (-9750 8650)(-8850 8650);
WIRE 16 -1 (-8850 9050)(-8850 8650);
WIRE 16 -1 (-8950 9050)(-8850 9050);
WIRE 16 -1 (-6500 9050)(-8850 9050);
FORCEPROP 2 LAST SIG_NAME BF_SMA3_SIG_IO_CONN
J 0
(-7910 9060);
DISPLAY 1.021277 (-7910 9060);
WIRE 16 -1 (-8950 8950)(-6500 8950);
FORCEPROP 2 LAST SIG_NAME BF_ANT3_IN
J 0
(-7910 8960);
DISPLAY 1.021277 (-7910 8960);
WIRE 16 -1 (-10600 9050)(-10000 9050);
WIRE 16 -1 (-10000 9050)(-9650 9050);
WIRE 16 -1 (-10000 8750)(-10000 9050);
WIRE 16 -1 (-9600 6800)(-9700 6800);
WIRE 16 -1 (-9700 6350)(-9700 6500);
WIRE 16 -1 (-9700 6800)(-9700 6500);
WIRE 16 -1 (-9700 6500)(-8800 6500);
WIRE 16 -1 (-8800 6500)(-8800 6900);
WIRE 16 -1 (-8900 6900)(-8800 6900);
WIRE 16 -1 (-6450 6900)(-8800 6900);
FORCEPROP 2 LAST SIG_NAME BF_SMA4_SIG_IO_CONN
J 0
(-7860 6910);
DISPLAY 1.021277 (-7860 6910);
WIRE 16 -1 (-8900 6800)(-6450 6800);
FORCEPROP 2 LAST SIG_NAME BF_ANT4_IN
J 0
(-7860 6810);
DISPLAY 1.021277 (-7860 6810);
WIRE 16 -1 (-12900 2600)(-10750 2600);
FORCEPROP 2 LAST SIG_NAME ANT2_OUT
J 0
(-12810 2610);
DISPLAY 1.021277 (-12810 2610);
WIRE 16 -1 (-3400 7600)(-3400 6900);
WIRE 16 -1 (-2700 6900)(-3400 6900);
WIRE 16 -1 (-6200 6900)(-3400 6900);
FORCEPROP 2 LAST SIG_NAME SMA4_SIG_IO_CONN
J 0
(-5310 6910);
DISPLAY 1.021277 (-5310 6910);
WIRE 16 -1 (-6200 6800)(-4900 6800);
FORCEPROP 2 LAST SIG_NAME ANT4_IN
J 0
(-5310 6810);
DISPLAY 1.021277 (-5310 6810);
WIRE 16 -1 (-6200 4650)(-4900 4650);
FORCEPROP 2 LAST SIG_NAME ANT1_IN
J 0
(-5310 4660);
DISPLAY 1.021277 (-5310 4660);
WIRE 16 -1 (-8850 2500)(-6400 2500);
FORCEPROP 2 LAST SIG_NAME BF_ANT2_IN
J 0
(-7810 2510);
DISPLAY 1.021277 (-7810 2510);
WIRE 16 -1 (-6250 8950)(-4950 8950);
FORCEPROP 2 LAST SIG_NAME ANT3_IN
J 0
(-5360 8960);
DISPLAY 1.021277 (-5360 8960);
WIRE 16 -1 (-3450 8200)(-3450 9050);
WIRE 16 -1 (-2750 9050)(-3450 9050);
WIRE 16 -1 (-6250 9050)(-3450 9050);
FORCEPROP 2 LAST SIG_NAME SMA3_SIG_IO_CONN
J 0
(-5360 9060);
DISPLAY 1.021277 (-5360 9060);
WIRE 16 -1 (-9550 2500)(-9650 2500);
WIRE 16 -1 (-9650 2050)(-9650 2200);
WIRE 16 -1 (-9650 2500)(-9650 2200);
WIRE 16 -1 (-9650 2200)(-8750 2200);
WIRE 16 -1 (-8750 2200)(-8750 2600);
WIRE 16 -1 (-8750 2600)(-6400 2600);
FORCEPROP 2 LAST SIG_NAME BF_SMA2_SIG_IO_CONN
J 0
(-7810 2610);
DISPLAY 1.021277 (-7810 2610);
WIRE 16 -1 (-8850 2600)(-8750 2600);
WIRE 16 -1 (-9600 4650)(-9700 4650);
WIRE 16 -1 (-9700 4200)(-9700 4350);
WIRE 16 -1 (-9700 4650)(-9700 4350);
WIRE 16 -1 (-9700 4350)(-8800 4350);
WIRE 16 -1 (-8800 4750)(-8800 4350);
WIRE 16 -1 (-8900 4750)(-8800 4750);
WIRE 16 -1 (-6450 4750)(-8800 4750);
FORCEPROP 2 LAST SIG_NAME BF_SMA1_SIG_IO_CONN
J 0
(-7860 4760);
DISPLAY 1.021277 (-7860 4760);
WIRE 16 -1 (-9900 2300)(-9900 2600);
WIRE 16 -1 (-9900 2600)(-9550 2600);
WIRE 16 -1 (-10500 2600)(-9900 2600);
WIRE 16 -1 (-9900 2050)(-9900 1950);
WIRE 16 -1 (-9950 4200)(-9950 4100);
WIRE 16 -1 (-9950 6350)(-9950 6250);
WIRE 16 -1 (-10000 8500)(-10000 8400);
WIRE 16 -1 (-10550 4750)(-9950 4750);
WIRE 16 -1 (-9950 4750)(-9600 4750);
WIRE 16 -1 (-9950 4450)(-9950 4750);
WIRE 16 -1 (-8900 4650)(-6450 4650);
FORCEPROP 2 LAST SIG_NAME BF_ANT1_IN
J 0
(-7860 4660);
DISPLAY 1.021277 (-7860 4660);
WIRE 16 -1 (-6150 2500)(-4850 2500);
FORCEPROP 2 LAST SIG_NAME ANT2_IN
J 0
(-5260 2510);
DISPLAY 1.021277 (-5260 2510);
DOT 1 (-9850 8850);
DOT 1 (-9900 1650);
DOT 1 (-9950 3800);
DOT 1 (-9950 5950);
DOT 1 (-8750 8500);
DOT 1 (-9700 4350);
DOT 1 (-9650 2200);
DOT 1 (-9750 8650);
DOT 1 (-9700 6500);
DOT 1 (-10000 9050);
DOT 1 (-9950 4750);
DOT 1 (-9900 2600);
DOT 1 (-9950 6900);
DOT 1 (-9800 6700);
DOT 1 (-9750 7000);
DOT 1 (-8450 9150);
DOT 1 (-8850 9050);
DOT 1 (-8400 7000);
DOT 1 (-8700 6350);
DOT 1 (-8800 6900);
DOT 1 (-8700 4200);
DOT 1 (-8800 4750);
DOT 1 (-8350 2700);
DOT 1 (-8650 2050);
DOT 1 (-9800 9150);
DOT 1 (-9850 4550);
DOT 1 (-9800 4850);
DOT 1 (-9800 2400);
DOT 1 (-9750 2700);
DOT 1 (-11150 3050);
DOT 1 (-11200 5200);
DOT 1 (-11200 7350);
DOT 1 (-11250 9500);
DOT 1 (-3450 9050);
DOT 1 (-2900 8700);
DOT 1 (-1900 8700);
DOT 1 (-3400 6900);
DOT 1 (-2850 6550);
DOT 1 (-1850 6550);
DOT 1 (-3400 4750);
DOT 1 (-2850 4400);
DOT 1 (-1850 4400);
DOT 1 (-3350 2600);
DOT 1 (-2800 2250);
DOT 1 (-1800 2250);
DOT 1 (-8400 4850);
DOT 1 (-8750 2600);
DOT 1 (-10000 8100);
FORCENOTE
SMA_CONN
(-8200 10250) 0;
DISPLAY LEFT (-8200 10250);
DISPLAY 4.914894 (-8200 10250);
FORCENOTE
PLACE R156 NEAR THE FPGA
(-11200 8950) 0;
DISPLAY LEFT (-11200 8950);
DISPLAY 0.808511 (-11200 8950);
FORCENOTE
PLACE R120 NEAR THE FPGA
(-11100 4650) 0;
DISPLAY LEFT (-11100 4650);
DISPLAY 0.808511 (-11100 4650);
FORCENOTE
PLACE R121 NEAR THE FPGA
(-11050 2500) 0;
DISPLAY LEFT (-11050 2500);
DISPLAY 0.808511 (-11050 2500);
FORCENOTE
PLACE R495,C318 CLOSE TO U16'S PIN
(-12000 1850) 0;
DISPLAY LEFT (-12000 1850);
DISPLAY 1.021277 (-12000 1850);
FORCENOTE
PLACE R494,C317 CLOSE TO U15'S PIN
(-12050 4000) 0;
DISPLAY LEFT (-12050 4000);
DISPLAY 1.021277 (-12050 4000);
FORCENOTE
PLACE R493,C311 CLOSE TO U14'S PIN
(-12050 6150) 0;
DISPLAY LEFT (-12050 6150);
DISPLAY 1.021277 (-12050 6150);
FORCENOTE
PLACE R157 NEAR THE FPGA
(-11100 6800) 0;
DISPLAY LEFT (-11100 6800);
DISPLAY 0.808511 (-11100 6800);
FORCENOTE
PLACE R492,C310 CLOSE TO U13'S PIN
(-12100 8300) 0;
DISPLAY LEFT (-12100 8300);
DISPLAY 1.021277 (-12100 8300);
QUIT
